(kicad_sch
	(version 20250114)
	(generator "eeschema")
	(generator_version "9.0")
	(paper "A3")
	(title_block
		(title "Antmicro Baseboard for Jetson AGX Thor")
		(date "2026-02-17")
		(rev "1.1.0")
		(company "Antmicro Ltd")
		(comment 1 "www.antmicro.com")
	)
	(text "EN input logic high 1.2V"
		(exclude_from_sim no)
		(at 62.738 211.328 0)
		(effects
			(font
				(size 1.27 1.27)
			)
			(justify left)
		)
	)
	(text "CSI x4"
		(exclude_from_sim no)
		(at 251.46 95.25 90)
		(effects
			(font
				(size 1.27 1.27)
			)
			(justify left bottom)
		)
	)
	(text "CSI x2"
		(exclude_from_sim no)
		(at 254.635 54.61 90)
		(effects
			(font
				(size 1.27 1.27)
			)
			(justify left bottom)
		)
	)
	(text "CSI x4"
		(exclude_from_sim no)
		(at 250.825 49.53 90)
		(effects
			(font
				(size 1.27 1.27)
			)
			(justify left bottom)
		)
	)
	(text "CSI x4"
		(exclude_from_sim no)
		(at 328.93 95.25 90)
		(effects
			(font
				(size 1.27 1.27)
			)
			(justify left bottom)
		)
	)
	(text "I2C addr: 0x70"
		(exclude_from_sim no)
		(at 121.666 114.3 0)
		(effects
			(font
				(size 1.27 1.27)
			)
		)
	)
	(text "Power switches"
		(exclude_from_sim no)
		(at 126.492 189.484 0)
		(effects
			(font
				(size 2.54 2.54)
				(thickness 0.8)
				(bold yes)
			)
			(justify left bottom)
		)
	)
	(text "CSI Connector B\n"
		(exclude_from_sim no)
		(at 338.836 19.558 0)
		(effects
			(font
				(size 2.54 2.54)
				(thickness 0.8)
				(bold yes)
			)
			(justify left bottom)
		)
	)
	(text "Level shifters"
		(exclude_from_sim no)
		(at 331.47 187.96 0)
		(effects
			(font
				(size 2.54 2.54)
				(thickness 0.8)
				(bold yes)
			)
			(justify left bottom)
		)
	)
	(text "CSI x2"
		(exclude_from_sim no)
		(at 332.74 100.33 90)
		(effects
			(font
				(size 1.27 1.27)
			)
			(justify left bottom)
		)
	)
	(text "ALL SWITCHES\n1.5A CURRENT LIMIT"
		(exclude_from_sim no)
		(at 141.732 198.374 0)
		(effects
			(font
				(size 1.27 1.27)
			)
			(justify left bottom)
		)
	)
	(text "I2C Mux"
		(exclude_from_sim no)
		(at 96.52 26.67 0)
		(effects
			(font
				(size 2.54 2.54)
				(thickness 0.8)
				(bold yes)
			)
			(justify left bottom)
		)
	)
	(text "CSI Connector A\n"
		(exclude_from_sim no)
		(at 271.018 19.05 0)
		(effects
			(font
				(size 2.54 2.54)
				(thickness 0.8)
				(bold yes)
			)
			(justify left bottom)
		)
	)
	(text "CSI x2"
		(exclude_from_sim no)
		(at 332.105 54.61 90)
		(effects
			(font
				(size 1.27 1.27)
			)
			(justify left bottom)
		)
	)
	(text "CSI x4"
		(exclude_from_sim no)
		(at 328.295 49.53 90)
		(effects
			(font
				(size 1.27 1.27)
			)
			(justify left bottom)
		)
	)
	(text "CSI x2"
		(exclude_from_sim no)
		(at 255.27 100.33 90)
		(effects
			(font
				(size 1.27 1.27)
			)
			(justify left bottom)
		)
	)
	(junction
		(at 207.01 248.92)
		(diameter 0)
		(color 0 0 0 0)
	)
	(junction
		(at 359.41 154.94)
		(diameter 0)
		(color 0 0 0 0)
	)
	(junction
		(at 323.85 149.86)
		(diameter 0)
		(color 0 0 0 0)
	)
	(junction
		(at 99.06 49.53)
		(diameter 0)
		(color 0 0 0 0)
	)
	(junction
		(at 361.95 68.58)
		(diameter 0)
		(color 0 0 0 0)
	)
	(junction
		(at 361.95 99.06)
		(diameter 0)
		(color 0 0 0 0)
	)
	(junction
		(at 334.01 196.85)
		(diameter 0)
		(color 0 0 0 0)
	)
	(junction
		(at 121.92 144.78)
		(diameter 0)
		(color 0 0 0 0)
	)
	(junction
		(at 85.09 96.52)
		(diameter 0)
		(color 0 0 0 0)
	)
	(junction
		(at 281.94 154.94)
		(diameter 0)
		(color 0 0 0 0)
	)
	(junction
		(at 359.41 149.86)
		(diameter 0)
		(color 0 0 0 0)
	)
	(junction
		(at 93.98 144.78)
		(diameter 0)
		(color 0 0 0 0)
	)
	(junction
		(at 97.79 215.9)
		(diameter 0)
		(color 0 0 0 0)
	)
	(junction
		(at 349.25 154.94)
		(diameter 0)
		(color 0 0 0 0)
	)
	(junction
		(at 344.17 149.86)
		(diameter 0)
		(color 0 0 0 0)
	)
	(junction
		(at 328.93 154.94)
		(diameter 0)
		(color 0 0 0 0)
	)
	(junction
		(at 133.35 144.78)
		(diameter 0)
		(color 0 0 0 0)
	)
	(junction
		(at 266.7 149.86)
		(diameter 0)
		(color 0 0 0 0)
	)
	(junction
		(at 113.03 231.14)
		(diameter 0)
		(color 0 0 0 0)
	)
	(junction
		(at 284.48 162.56)
		(diameter 0)
		(color 0 0 0 0)
	)
	(junction
		(at 284.48 99.06)
		(diameter 0)
		(color 0 0 0 0)
	)
	(junction
		(at 113.03 213.36)
		(diameter 0)
		(color 0 0 0 0)
	)
	(junction
		(at 102.87 201.93)
		(diameter 0)
		(color 0 0 0 0)
	)
	(junction
		(at 92.71 215.9)
		(diameter 0)
		(color 0 0 0 0)
	)
	(junction
		(at 97.79 248.92)
		(diameter 0)
		(color 0 0 0 0)
	)
	(junction
		(at 246.38 149.86)
		(diameter 0)
		(color 0 0 0 0)
	)
	(junction
		(at 372.11 196.85)
		(diameter 0)
		(color 0 0 0 0)
	)
	(junction
		(at 284.48 60.96)
		(diameter 0)
		(color 0 0 0 0)
	)
	(junction
		(at 102.87 233.68)
		(diameter 0)
		(color 0 0 0 0)
	)
	(junction
		(at 128.27 144.78)
		(diameter 0)
		(color 0 0 0 0)
	)
	(junction
		(at 372.11 226.06)
		(diameter 0)
		(color 0 0 0 0)
	)
	(junction
		(at 110.49 109.22)
		(diameter 0)
		(color 0 0 0 0)
	)
	(junction
		(at 207.01 215.9)
		(diameter 0)
		(color 0 0 0 0)
	)
	(junction
		(at 284.48 106.68)
		(diameter 0)
		(color 0 0 0 0)
	)
	(junction
		(at 341.63 238.76)
		(diameter 0)
		(color 0 0 0 0)
	)
	(junction
		(at 85.09 144.78)
		(diameter 0)
		(color 0 0 0 0)
	)
	(junction
		(at 334.01 226.06)
		(diameter 0)
		(color 0 0 0 0)
	)
	(junction
		(at 222.25 231.14)
		(diameter 0)
		(color 0 0 0 0)
	)
	(junction
		(at 284.48 76.2)
		(diameter 0)
		(color 0 0 0 0)
	)
	(junction
		(at 361.95 60.96)
		(diameter 0)
		(color 0 0 0 0)
	)
	(junction
		(at 130.81 144.78)
		(diameter 0)
		(color 0 0 0 0)
	)
	(junction
		(at 361.95 162.56)
		(diameter 0)
		(color 0 0 0 0)
	)
	(junction
		(at 212.09 233.68)
		(diameter 0)
		(color 0 0 0 0)
	)
	(junction
		(at 284.48 160.02)
		(diameter 0)
		(color 0 0 0 0)
	)
	(junction
		(at 361.95 76.2)
		(diameter 0)
		(color 0 0 0 0)
	)
	(junction
		(at 281.94 149.86)
		(diameter 0)
		(color 0 0 0 0)
	)
	(junction
		(at 271.78 154.94)
		(diameter 0)
		(color 0 0 0 0)
	)
	(junction
		(at 222.25 213.36)
		(diameter 0)
		(color 0 0 0 0)
	)
	(junction
		(at 284.48 68.58)
		(diameter 0)
		(color 0 0 0 0)
	)
	(junction
		(at 201.93 215.9)
		(diameter 0)
		(color 0 0 0 0)
	)
	(junction
		(at 361.95 160.02)
		(diameter 0)
		(color 0 0 0 0)
	)
	(junction
		(at 251.46 154.94)
		(diameter 0)
		(color 0 0 0 0)
	)
	(junction
		(at 361.95 106.68)
		(diameter 0)
		(color 0 0 0 0)
	)
	(junction
		(at 212.09 201.93)
		(diameter 0)
		(color 0 0 0 0)
	)
	(junction
		(at 96.52 144.78)
		(diameter 0)
		(color 0 0 0 0)
	)
	(junction
		(at 91.44 144.78)
		(diameter 0)
		(color 0 0 0 0)
	)
	(junction
		(at 110.49 101.6)
		(diameter 0)
		(color 0 0 0 0)
	)
	(junction
		(at 341.63 209.55)
		(diameter 0)
		(color 0 0 0 0)
	)
	(no_connect
		(at 287.02 66.04)
	)
	(no_connect
		(at 287.02 71.12)
	)
	(no_connect
		(at 364.49 144.78)
	)
	(no_connect
		(at 364.49 139.7)
	)
	(no_connect
		(at 287.02 124.46)
	)
	(no_connect
		(at 364.49 73.66)
	)
	(no_connect
		(at 364.49 121.92)
	)
	(no_connect
		(at 287.02 121.92)
	)
	(no_connect
		(at 287.02 144.78)
	)
	(no_connect
		(at 364.49 66.04)
	)
	(no_connect
		(at 364.49 114.3)
	)
	(no_connect
		(at 364.49 142.24)
	)
	(no_connect
		(at 287.02 109.22)
	)
	(no_connect
		(at 287.02 73.66)
	)
	(no_connect
		(at 364.49 119.38)
	)
	(no_connect
		(at 287.02 127)
	)
	(no_connect
		(at 364.49 124.46)
	)
	(no_connect
		(at 364.49 109.22)
	)
	(no_connect
		(at 364.49 63.5)
	)
	(no_connect
		(at 364.49 71.12)
	)
	(no_connect
		(at 111.76 106.68)
	)
	(no_connect
		(at 364.49 147.32)
	)
	(no_connect
		(at 287.02 147.32)
	)
	(no_connect
		(at 287.02 63.5)
	)
	(no_connect
		(at 287.02 142.24)
	)
	(no_connect
		(at 364.49 127)
	)
	(no_connect
		(at 287.02 114.3)
	)
	(no_connect
		(at 287.02 139.7)
	)
	(no_connect
		(at 287.02 119.38)
	)
	(bus_entry
		(at 336.55 97.79)
		(size 1.27 -1.27)
		(stroke
			(width 0)
			(type default)
		)
	)
	(bus_entry
		(at 259.08 41.91)
		(size 1.27 -1.27)
		(stroke
			(width 0)
			(type default)
		)
	)
	(bus_entry
		(at 48.26 210.82)
		(size -1.27 1.27)
		(stroke
			(width 0)
			(type default)
		)
	)
	(bus_entry
		(at 259.08 36.83)
		(size 1.27 -1.27)
		(stroke
			(width 0)
			(type default)
		)
	)
	(bus_entry
		(at 336.55 95.25)
		(size 1.27 -1.27)
		(stroke
			(width 0)
			(type default)
		)
	)
	(bus_entry
		(at 259.08 59.69)
		(size 1.27 -1.27)
		(stroke
			(width 0)
			(type default)
		)
	)
	(bus_entry
		(at 48.26 205.74)
		(size -1.27 1.27)
		(stroke
			(width 0)
			(type default)
		)
	)
	(bus_entry
		(at 336.55 59.69)
		(size 1.27 -1.27)
		(stroke
			(width 0)
			(type default)
		)
	)
	(bus_entry
		(at 259.08 34.29)
		(size 1.27 -1.27)
		(stroke
			(width 0)
			(type default)
		)
	)
	(bus_entry
		(at 336.55 102.87)
		(size 1.27 -1.27)
		(stroke
			(width 0)
			(type default)
		)
	)
	(bus_entry
		(at 336.55 52.07)
		(size 1.27 -1.27)
		(stroke
			(width 0)
			(type default)
		)
	)
	(bus_entry
		(at 259.08 90.17)
		(size 1.27 -1.27)
		(stroke
			(width 0)
			(type default)
		)
	)
	(bus_entry
		(at 259.08 44.45)
		(size 1.27 -1.27)
		(stroke
			(width 0)
			(type default)
		)
	)
	(bus_entry
		(at 259.08 80.01)
		(size 1.27 -1.27)
		(stroke
			(width 0)
			(type default)
		)
	)
	(bus_entry
		(at 336.55 80.01)
		(size 1.27 -1.27)
		(stroke
			(width 0)
			(type default)
		)
	)
	(bus_entry
		(at 67.31 66.04)
		(size -1.27 -1.27)
		(stroke
			(width 0)
			(type default)
		)
	)
	(bus_entry
		(at 336.55 85.09)
		(size 1.27 -1.27)
		(stroke
			(width 0)
			(type default)
		)
	)
	(bus_entry
		(at 259.08 102.87)
		(size 1.27 -1.27)
		(stroke
			(width 0)
			(type default)
		)
	)
	(bus_entry
		(at 259.08 85.09)
		(size 1.27 -1.27)
		(stroke
			(width 0)
			(type default)
		)
	)
	(bus_entry
		(at 259.08 95.25)
		(size 1.27 -1.27)
		(stroke
			(width 0)
			(type default)
		)
	)
	(bus_entry
		(at 48.26 218.44)
		(size -1.27 1.27)
		(stroke
			(width 0)
			(type default)
		)
	)
	(bus_entry
		(at 336.55 57.15)
		(size 1.27 -1.27)
		(stroke
			(width 0)
			(type default)
		)
	)
	(bus_entry
		(at 259.08 39.37)
		(size 1.27 -1.27)
		(stroke
			(width 0)
			(type default)
		)
	)
	(bus_entry
		(at 259.08 92.71)
		(size 1.27 -1.27)
		(stroke
			(width 0)
			(type default)
		)
	)
	(bus_entry
		(at 336.55 44.45)
		(size 1.27 -1.27)
		(stroke
			(width 0)
			(type default)
		)
	)
	(bus_entry
		(at 336.55 82.55)
		(size 1.27 -1.27)
		(stroke
			(width 0)
			(type default)
		)
	)
	(bus_entry
		(at 259.08 87.63)
		(size 1.27 -1.27)
		(stroke
			(width 0)
			(type default)
		)
	)
	(bus_entry
		(at 259.08 105.41)
		(size 1.27 -1.27)
		(stroke
			(width 0)
			(type default)
		)
	)
	(bus_entry
		(at 336.55 46.99)
		(size 1.27 -1.27)
		(stroke
			(width 0)
			(type default)
		)
	)
	(bus_entry
		(at 259.08 46.99)
		(size 1.27 -1.27)
		(stroke
			(width 0)
			(type default)
		)
	)
	(bus_entry
		(at 48.26 215.9)
		(size -1.27 1.27)
		(stroke
			(width 0)
			(type default)
		)
	)
	(bus_entry
		(at 259.08 49.53)
		(size 1.27 -1.27)
		(stroke
			(width 0)
			(type default)
		)
	)
	(bus_entry
		(at 336.55 41.91)
		(size 1.27 -1.27)
		(stroke
			(width 0)
			(type default)
		)
	)
	(bus_entry
		(at 336.55 87.63)
		(size 1.27 -1.27)
		(stroke
			(width 0)
			(type default)
		)
	)
	(bus_entry
		(at 336.55 92.71)
		(size 1.27 -1.27)
		(stroke
			(width 0)
			(type default)
		)
	)
	(bus_entry
		(at 336.55 36.83)
		(size 1.27 -1.27)
		(stroke
			(width 0)
			(type default)
		)
	)
	(bus_entry
		(at 336.55 90.17)
		(size 1.27 -1.27)
		(stroke
			(width 0)
			(type default)
		)
	)
	(bus_entry
		(at 259.08 82.55)
		(size 1.27 -1.27)
		(stroke
			(width 0)
			(type default)
		)
	)
	(bus_entry
		(at 48.26 223.52)
		(size -1.27 1.27)
		(stroke
			(width 0)
			(type default)
		)
	)
	(bus_entry
		(at 336.55 49.53)
		(size 1.27 -1.27)
		(stroke
			(width 0)
			(type default)
		)
	)
	(bus_entry
		(at 67.31 68.58)
		(size -1.27 -1.27)
		(stroke
			(width 0)
			(type default)
		)
	)
	(bus_entry
		(at 48.26 208.28)
		(size -1.27 1.27)
		(stroke
			(width 0)
			(type default)
		)
	)
	(bus_entry
		(at 259.08 57.15)
		(size 1.27 -1.27)
		(stroke
			(width 0)
			(type default)
		)
	)
	(bus_entry
		(at 259.08 97.79)
		(size 1.27 -1.27)
		(stroke
			(width 0)
			(type default)
		)
	)
	(bus_entry
		(at 336.55 105.41)
		(size 1.27 -1.27)
		(stroke
			(width 0)
			(type default)
		)
	)
	(bus_entry
		(at 48.26 220.98)
		(size -1.27 1.27)
		(stroke
			(width 0)
			(type default)
		)
	)
	(bus_entry
		(at 48.26 213.36)
		(size -1.27 1.27)
		(stroke
			(width 0)
			(type default)
		)
	)
	(bus_entry
		(at 259.08 52.07)
		(size 1.27 -1.27)
		(stroke
			(width 0)
			(type default)
		)
	)
	(bus_entry
		(at 336.55 34.29)
		(size 1.27 -1.27)
		(stroke
			(width 0)
			(type default)
		)
	)
	(bus_entry
		(at 336.55 39.37)
		(size 1.27 -1.27)
		(stroke
			(width 0)
			(type default)
		)
	)
	(bus
		(pts
			(xy 48.26 204.47) (xy 48.26 205.74)
		)
		(stroke
			(width 0)
			(type default)
		)
	)
	(wire
		(pts
			(xy 80.01 171.45) (xy 99.06 171.45)
		)
		(stroke
			(width 0)
			(type default)
		)
	)
	(bus
		(pts
			(xy 49.53 203.2) (xy 48.26 204.47)
		)
		(stroke
			(width 0)
			(type default)
		)
	)
	(wire
		(pts
			(xy 91.44 156.21) (xy 91.44 162.56)
		)
		(stroke
			(width 0)
			(type default)
		)
	)
	(wire
		(pts
			(xy 337.82 33.02) (xy 364.49 33.02)
		)
		(stroke
			(width 0)
			(type default)
		)
	)
	(wire
		(pts
			(xy 132.08 106.68) (xy 147.32 106.68)
		)
		(stroke
			(width 0)
			(type default)
		)
	)
	(wire
		(pts
			(xy 334.01 196.85) (xy 334.01 198.12)
		)
		(stroke
			(width 0)
			(type default)
		)
	)
	(wire
		(pts
			(xy 266.7 161.29) (xy 266.7 162.56)
		)
		(stroke
			(width 0)
			(type default)
		)
	)
	(wire
		(pts
			(xy 102.87 233.68) (xy 102.87 234.95)
		)
		(stroke
			(width 0)
			(type default)
		)
	)
	(wire
		(pts
			(xy 207.01 215.9) (xy 207.01 248.92)
		)
		(stroke
			(width 0)
			(type default)
		)
	)
	(wire
		(pts
			(xy 328.93 167.64) (xy 328.93 168.91)
		)
		(stroke
			(width 0)
			(type default)
		)
	)
	(wire
		(pts
			(xy 316.23 241.3) (xy 342.9 241.3)
		)
		(stroke
			(width 0)
			(type default)
		)
	)
	(wire
		(pts
			(xy 302.26 154.94) (xy 328.93 154.94)
		)
		(stroke
			(width 0)
			(type default)
		)
	)
	(wire
		(pts
			(xy 354.33 129.54) (xy 364.49 129.54)
		)
		(stroke
			(width 0)
			(type default)
		)
	)
	(wire
		(pts
			(xy 134.62 213.36) (xy 149.86 213.36)
		)
		(stroke
			(width 0)
			(type default)
		)
	)
	(wire
		(pts
			(xy 342.9 209.55) (xy 341.63 209.55)
		)
		(stroke
			(width 0)
			(type default)
		)
	)
	(wire
		(pts
			(xy 316.23 243.84) (xy 342.9 243.84)
		)
		(stroke
			(width 0)
			(type default)
		)
	)
	(wire
		(pts
			(xy 132.08 86.36) (xy 147.32 86.36)
		)
		(stroke
			(width 0)
			(type default)
		)
	)
	(wire
		(pts
			(xy 284.48 99.06) (xy 284.48 106.68)
		)
		(stroke
			(width 0)
			(type default)
		)
	)
	(wire
		(pts
			(xy 93.98 91.44) (xy 111.76 91.44)
		)
		(stroke
			(width 0)
			(type default)
		)
	)
	(wire
		(pts
			(xy 337.82 88.9) (xy 364.49 88.9)
		)
		(stroke
			(width 0)
			(type default)
		)
	)
	(polyline
		(pts
			(xy 299.72 180.34) (xy 407.67 180.34)
		)
		(stroke
			(width 0)
			(type default)
		)
	)
	(wire
		(pts
			(xy 361.95 106.68) (xy 361.95 160.02)
		)
		(stroke
			(width 0)
			(type default)
		)
	)
	(wire
		(pts
			(xy 222.25 208.28) (xy 222.25 213.36)
		)
		(stroke
			(width 0)
			(type default)
		)
	)
	(wire
		(pts
			(xy 96.52 156.21) (xy 96.52 168.91)
		)
		(stroke
			(width 0)
			(type default)
		)
	)
	(wire
		(pts
			(xy 133.35 144.78) (xy 133.35 151.13)
		)
		(stroke
			(width 0)
			(type default)
		)
	)
	(wire
		(pts
			(xy 149.86 219.71) (xy 149.86 220.98)
		)
		(stroke
			(width 0)
			(type default)
		)
	)
	(wire
		(pts
			(xy 281.94 152.4) (xy 281.94 149.86)
		)
		(stroke
			(width 0)
			(type default)
		)
	)
	(wire
		(pts
			(xy 97.79 255.27) (xy 97.79 256.54)
		)
		(stroke
			(width 0)
			(type default)
		)
	)
	(bus
		(pts
			(xy 66.04 64.77) (xy 64.77 63.5)
		)
		(stroke
			(width 0)
			(type default)
		)
	)
	(bus
		(pts
			(xy 48.26 208.28) (xy 48.26 210.82)
		)
		(stroke
			(width 0)
			(type default)
		)
	)
	(bus
		(pts
			(xy 257.81 62.23) (xy 252.73 62.23)
		)
		(stroke
			(width 0)
			(type default)
		)
	)
	(bus
		(pts
			(xy 48.26 210.82) (xy 48.26 213.36)
		)
		(stroke
			(width 0)
			(type default)
		)
	)
	(wire
		(pts
			(xy 128.27 156.21) (xy 128.27 162.56)
		)
		(stroke
			(width 0)
			(type default)
		)
	)
	(bus
		(pts
			(xy 336.55 60.96) (xy 335.28 62.23)
		)
		(stroke
			(width 0)
			(type default)
		)
	)
	(wire
		(pts
			(xy 110.49 99.06) (xy 111.76 99.06)
		)
		(stroke
			(width 0)
			(type default)
		)
	)
	(wire
		(pts
			(xy 359.41 154.94) (xy 364.49 154.94)
		)
		(stroke
			(width 0)
			(type default)
		)
	)
	(wire
		(pts
			(xy 128.27 144.78) (xy 128.27 151.13)
		)
		(stroke
			(width 0)
			(type default)
		)
	)
	(wire
		(pts
			(xy 344.17 161.29) (xy 344.17 162.56)
		)
		(stroke
			(width 0)
			(type default)
		)
	)
	(wire
		(pts
			(xy 21.59 207.01) (xy 46.99 207.01)
		)
		(stroke
			(width 0)
			(type default)
		)
	)
	(wire
		(pts
			(xy 133.35 144.78) (xy 135.89 144.78)
		)
		(stroke
			(width 0)
			(type default)
		)
	)
	(wire
		(pts
			(xy 243.84 210.82) (xy 259.08 210.82)
		)
		(stroke
			(width 0)
			(type default)
		)
	)
	(wire
		(pts
			(xy 219.71 233.68) (xy 212.09 233.68)
		)
		(stroke
			(width 0)
			(type default)
		)
	)
	(wire
		(pts
			(xy 102.87 200.66) (xy 102.87 201.93)
		)
		(stroke
			(width 0)
			(type default)
		)
	)
	(wire
		(pts
			(xy 349.25 154.94) (xy 359.41 154.94)
		)
		(stroke
			(width 0)
			(type default)
		)
	)
	(wire
		(pts
			(xy 337.82 101.6) (xy 364.49 101.6)
		)
		(stroke
			(width 0)
			(type default)
		)
	)
	(wire
		(pts
			(xy 113.03 231.14) (xy 134.62 231.14)
		)
		(stroke
			(width 0)
			(type default)
		)
	)
	(polyline
		(pts
			(xy 328.93 31.75) (xy 328.93 59.69)
		)
		(stroke
			(width 0)
			(type solid)
		)
	)
	(wire
		(pts
			(xy 364.49 152.4) (xy 359.41 152.4)
		)
		(stroke
			(width 0)
			(type default)
		)
	)
	(wire
		(pts
			(xy 212.09 200.66) (xy 212.09 201.93)
		)
		(stroke
			(width 0)
			(type default)
		)
	)
	(wire
		(pts
			(xy 361.95 162.56) (xy 364.49 162.56)
		)
		(stroke
			(width 0)
			(type default)
		)
	)
	(wire
		(pts
			(xy 271.78 154.94) (xy 281.94 154.94)
		)
		(stroke
			(width 0)
			(type default)
		)
	)
	(wire
		(pts
			(xy 284.48 162.56) (xy 287.02 162.56)
		)
		(stroke
			(width 0)
			(type default)
		)
	)
	(wire
		(pts
			(xy 201.93 208.28) (xy 201.93 215.9)
		)
		(stroke
			(width 0)
			(type default)
		)
	)
	(wire
		(pts
			(xy 251.46 161.29) (xy 251.46 162.56)
		)
		(stroke
			(width 0)
			(type default)
		)
	)
	(wire
		(pts
			(xy 245.11 248.92) (xy 245.11 254)
		)
		(stroke
			(width 0)
			(type default)
		)
	)
	(wire
		(pts
			(xy 207.01 255.27) (xy 207.01 256.54)
		)
		(stroke
			(width 0)
			(type default)
		)
	)
	(wire
		(pts
			(xy 246.38 161.29) (xy 246.38 162.56)
		)
		(stroke
			(width 0)
			(type default)
		)
	)
	(wire
		(pts
			(xy 97.79 215.9) (xy 97.79 248.92)
		)
		(stroke
			(width 0)
			(type default)
		)
	)
	(wire
		(pts
			(xy 334.01 134.62) (xy 349.25 134.62)
		)
		(stroke
			(width 0)
			(type default)
		)
	)
	(wire
		(pts
			(xy 224.79 154.94) (xy 251.46 154.94)
		)
		(stroke
			(width 0)
			(type default)
		)
	)
	(wire
		(pts
			(xy 222.25 213.36) (xy 222.25 231.14)
		)
		(stroke
			(width 0)
			(type default)
		)
	)
	(bus
		(pts
			(xy 336.55 95.25) (xy 336.55 92.71)
		)
		(stroke
			(width 0)
			(type default)
		)
	)
	(wire
		(pts
			(xy 113.03 213.36) (xy 119.38 213.36)
		)
		(stroke
			(width 0)
			(type default)
		)
	)
	(wire
		(pts
			(xy 91.44 144.78) (xy 91.44 151.13)
		)
		(stroke
			(width 0)
			(type default)
		)
	)
	(wire
		(pts
			(xy 76.2 134.62) (xy 76.2 135.89)
		)
		(stroke
			(width 0)
			(type default)
		)
	)
	(wire
		(pts
			(xy 337.82 81.28) (xy 364.49 81.28)
		)
		(stroke
			(width 0)
			(type default)
		)
	)
	(wire
		(pts
			(xy 341.63 217.17) (xy 342.9 217.17)
		)
		(stroke
			(width 0)
			(type default)
		)
	)
	(wire
		(pts
			(xy 135.89 156.21) (xy 135.89 171.45)
		)
		(stroke
			(width 0)
			(type default)
		)
	)
	(wire
		(pts
			(xy 132.08 63.5) (xy 142.24 63.5)
		)
		(stroke
			(width 0)
			(type default)
		)
	)
	(wire
		(pts
			(xy 251.46 154.94) (xy 271.78 154.94)
		)
		(stroke
			(width 0)
			(type default)
		)
	)
	(wire
		(pts
			(xy 361.95 99.06) (xy 364.49 99.06)
		)
		(stroke
			(width 0)
			(type default)
		)
	)
	(wire
		(pts
			(xy 114.3 140.97) (xy 114.3 144.78)
		)
		(stroke
			(width 0)
			(type default)
		)
	)
	(wire
		(pts
			(xy 132.08 78.74) (xy 142.24 78.74)
		)
		(stroke
			(width 0)
			(type default)
		)
	)
	(wire
		(pts
			(xy 96.52 144.78) (xy 96.52 151.13)
		)
		(stroke
			(width 0)
			(type default)
		)
	)
	(wire
		(pts
			(xy 76.2 140.97) (xy 76.2 144.78)
		)
		(stroke
			(width 0)
			(type default)
		)
	)
	(wire
		(pts
			(xy 337.82 38.1) (xy 364.49 38.1)
		)
		(stroke
			(width 0)
			(type default)
		)
	)
	(wire
		(pts
			(xy 361.95 160.02) (xy 364.49 160.02)
		)
		(stroke
			(width 0)
			(type default)
		)
	)
	(polyline
		(pts
			(xy 251.46 77.47) (xy 251.46 105.41)
		)
		(stroke
			(width 0)
			(type solid)
		)
	)
	(wire
		(pts
			(xy 134.62 243.84) (xy 149.86 243.84)
		)
		(stroke
			(width 0)
			(type default)
		)
	)
	(wire
		(pts
			(xy 337.82 43.18) (xy 364.49 43.18)
		)
		(stroke
			(width 0)
			(type default)
		)
	)
	(wire
		(pts
			(xy 363.22 238.76) (xy 364.49 238.76)
		)
		(stroke
			(width 0)
			(type default)
		)
	)
	(wire
		(pts
			(xy 363.22 217.17) (xy 364.49 217.17)
		)
		(stroke
			(width 0)
			(type default)
		)
	)
	(polyline
		(pts
			(xy 251.46 31.75) (xy 251.46 59.69)
		)
		(stroke
			(width 0)
			(type solid)
		)
	)
	(wire
		(pts
			(xy 271.78 161.29) (xy 271.78 162.56)
		)
		(stroke
			(width 0)
			(type default)
		)
	)
	(wire
		(pts
			(xy 133.35 168.91) (xy 116.84 168.91)
		)
		(stroke
			(width 0)
			(type default)
		)
	)
	(wire
		(pts
			(xy 109.22 53.34) (xy 109.22 49.53)
		)
		(stroke
			(width 0)
			(type default)
		)
	)
	(wire
		(pts
			(xy 132.08 93.98) (xy 147.32 93.98)
		)
		(stroke
			(width 0)
			(type default)
		)
	)
	(wire
		(pts
			(xy 361.95 53.34) (xy 361.95 60.96)
		)
		(stroke
			(width 0)
			(type default)
		)
	)
	(wire
		(pts
			(xy 256.54 137.16) (xy 271.78 137.16)
		)
		(stroke
			(width 0)
			(type default)
		)
	)
	(wire
		(pts
			(xy 276.86 134.62) (xy 287.02 134.62)
		)
		(stroke
			(width 0)
			(type default)
		)
	)
	(wire
		(pts
			(xy 284.48 76.2) (xy 284.48 99.06)
		)
		(stroke
			(width 0)
			(type default)
		)
	)
	(wire
		(pts
			(xy 85.09 87.63) (xy 85.09 96.52)
		)
		(stroke
			(width 0)
			(type default)
		)
	)
	(wire
		(pts
			(xy 85.09 80.01) (xy 85.09 82.55)
		)
		(stroke
			(width 0)
			(type default)
		)
	)
	(wire
		(pts
			(xy 207.01 215.9) (xy 228.6 215.9)
		)
		(stroke
			(width 0)
			(type default)
		)
	)
	(wire
		(pts
			(xy 207.01 248.92) (xy 228.6 248.92)
		)
		(stroke
			(width 0)
			(type default)
		)
	)
	(wire
		(pts
			(xy 323.85 161.29) (xy 323.85 162.56)
		)
		(stroke
			(width 0)
			(type default)
		)
	)
	(wire
		(pts
			(xy 323.85 167.64) (xy 323.85 168.91)
		)
		(stroke
			(width 0)
			(type default)
		)
	)
	(wire
		(pts
			(xy 363.22 214.63) (xy 381 214.63)
		)
		(stroke
			(width 0)
			(type default)
		)
	)
	(bus
		(pts
			(xy 48.26 213.36) (xy 48.26 215.9)
		)
		(stroke
			(width 0)
			(type default)
		)
	)
	(wire
		(pts
			(xy 328.93 154.94) (xy 349.25 154.94)
		)
		(stroke
			(width 0)
			(type default)
		)
	)
	(bus
		(pts
			(xy 259.08 80.01) (xy 259.08 82.55)
		)
		(stroke
			(width 0)
			(type default)
		)
	)
	(wire
		(pts
			(xy 246.38 149.86) (xy 266.7 149.86)
		)
		(stroke
			(width 0)
			(type default)
		)
	)
	(wire
		(pts
			(xy 337.82 48.26) (xy 364.49 48.26)
		)
		(stroke
			(width 0)
			(type default)
		)
	)
	(wire
		(pts
			(xy 361.95 76.2) (xy 361.95 99.06)
		)
		(stroke
			(width 0)
			(type default)
		)
	)
	(wire
		(pts
			(xy 243.84 215.9) (xy 245.11 215.9)
		)
		(stroke
			(width 0)
			(type default)
		)
	)
	(wire
		(pts
			(xy 243.84 243.84) (xy 259.08 243.84)
		)
		(stroke
			(width 0)
			(type default)
		)
	)
	(wire
		(pts
			(xy 132.08 60.96) (xy 142.24 60.96)
		)
		(stroke
			(width 0)
			(type default)
		)
	)
	(wire
		(pts
			(xy 109.22 49.53) (xy 99.06 49.53)
		)
		(stroke
			(width 0)
			(type default)
		)
	)
	(wire
		(pts
			(xy 334.01 224.79) (xy 334.01 226.06)
		)
		(stroke
			(width 0)
			(type default)
		)
	)
	(wire
		(pts
			(xy 97.79 248.92) (xy 119.38 248.92)
		)
		(stroke
			(width 0)
			(type default)
		)
	)
	(wire
		(pts
			(xy 256.54 129.54) (xy 271.78 129.54)
		)
		(stroke
			(width 0)
			(type default)
		)
	)
	(bus
		(pts
			(xy 259.08 60.96) (xy 257.81 62.23)
		)
		(stroke
			(width 0)
			(type default)
		)
	)
	(wire
		(pts
			(xy 110.49 101.6) (xy 110.49 109.22)
		)
		(stroke
			(width 0)
			(type default)
		)
	)
	(wire
		(pts
			(xy 260.35 33.02) (xy 287.02 33.02)
		)
		(stroke
			(width 0)
			(type default)
		)
	)
	(bus
		(pts
			(xy 336.55 36.83) (xy 336.55 39.37)
		)
		(stroke
			(width 0)
			(type default)
		)
	)
	(wire
		(pts
			(xy 90.17 68.58) (xy 111.76 68.58)
		)
		(stroke
			(width 0)
			(type default)
		)
	)
	(wire
		(pts
			(xy 99.06 156.21) (xy 99.06 171.45)
		)
		(stroke
			(width 0)
			(type default)
		)
	)
	(bus
		(pts
			(xy 259.08 59.69) (xy 259.08 57.15)
		)
		(stroke
			(width 0)
			(type default)
		)
	)
	(wire
		(pts
			(xy 80.01 165.1) (xy 93.98 165.1)
		)
		(stroke
			(width 0)
			(type default)
		)
	)
	(wire
		(pts
			(xy 149.86 213.36) (xy 149.86 214.63)
		)
		(stroke
			(width 0)
			(type default)
		)
	)
	(bus
		(pts
			(xy 336.55 105.41) (xy 336.55 106.68)
		)
		(stroke
			(width 0)
			(type default)
		)
	)
	(wire
		(pts
			(xy 85.09 99.06) (xy 85.09 96.52)
		)
		(stroke
			(width 0)
			(type default)
		)
	)
	(wire
		(pts
			(xy 116.84 171.45) (xy 135.89 171.45)
		)
		(stroke
			(width 0)
			(type default)
		)
	)
	(wire
		(pts
			(xy 130.81 144.78) (xy 133.35 144.78)
		)
		(stroke
			(width 0)
			(type default)
		)
	)
	(wire
		(pts
			(xy 110.49 109.22) (xy 111.76 109.22)
		)
		(stroke
			(width 0)
			(type default)
		)
	)
	(bus
		(pts
			(xy 336.55 52.07) (xy 336.55 49.53)
		)
		(stroke
			(width 0)
			(type default)
		)
	)
	(wire
		(pts
			(xy 364.49 209.55) (xy 364.49 196.85)
		)
		(stroke
			(width 0)
			(type default)
		)
	)
	(wire
		(pts
			(xy 114.3 134.62) (xy 114.3 135.89)
		)
		(stroke
			(width 0)
			(type default)
		)
	)
	(bus
		(pts
			(xy 335.28 62.23) (xy 330.2 62.23)
		)
		(stroke
			(width 0)
			(type default)
		)
	)
	(wire
		(pts
			(xy 222.25 213.36) (xy 228.6 213.36)
		)
		(stroke
			(width 0)
			(type default)
		)
	)
	(wire
		(pts
			(xy 334.01 129.54) (xy 349.25 129.54)
		)
		(stroke
			(width 0)
			(type default)
		)
	)
	(wire
		(pts
			(xy 90.17 66.04) (xy 111.76 66.04)
		)
		(stroke
			(width 0)
			(type default)
		)
	)
	(wire
		(pts
			(xy 132.08 71.12) (xy 142.24 71.12)
		)
		(stroke
			(width 0)
			(type default)
		)
	)
	(wire
		(pts
			(xy 99.06 55.88) (xy 99.06 57.15)
		)
		(stroke
			(width 0)
			(type default)
		)
	)
	(wire
		(pts
			(xy 349.25 161.29) (xy 349.25 162.56)
		)
		(stroke
			(width 0)
			(type default)
		)
	)
	(wire
		(pts
			(xy 361.95 163.83) (xy 361.95 162.56)
		)
		(stroke
			(width 0)
			(type default)
		)
	)
	(wire
		(pts
			(xy 364.49 226.06) (xy 372.11 226.06)
		)
		(stroke
			(width 0)
			(type default)
		)
	)
	(wire
		(pts
			(xy 121.92 134.62) (xy 121.92 135.89)
		)
		(stroke
			(width 0)
			(type default)
		)
	)
	(wire
		(pts
			(xy 361.95 76.2) (xy 364.49 76.2)
		)
		(stroke
			(width 0)
			(type default)
		)
	)
	(wire
		(pts
			(xy 284.48 60.96) (xy 287.02 60.96)
		)
		(stroke
			(width 0)
			(type default)
		)
	)
	(wire
		(pts
			(xy 361.95 68.58) (xy 361.95 76.2)
		)
		(stroke
			(width 0)
			(type default)
		)
	)
	(wire
		(pts
			(xy 110.49 233.68) (xy 102.87 233.68)
		)
		(stroke
			(width 0)
			(type default)
		)
	)
	(wire
		(pts
			(xy 113.03 231.14) (xy 113.03 246.38)
		)
		(stroke
			(width 0)
			(type default)
		)
	)
	(wire
		(pts
			(xy 281.94 157.48) (xy 287.02 157.48)
		)
		(stroke
			(width 0)
			(type default)
		)
	)
	(wire
		(pts
			(xy 219.71 201.93) (xy 212.09 201.93)
		)
		(stroke
			(width 0)
			(type default)
		)
	)
	(wire
		(pts
			(xy 260.35 78.74) (xy 287.02 78.74)
		)
		(stroke
			(width 0)
			(type default)
		)
	)
	(wire
		(pts
			(xy 260.35 43.18) (xy 287.02 43.18)
		)
		(stroke
			(width 0)
			(type default)
		)
	)
	(bus
		(pts
			(xy 259.08 106.68) (xy 257.81 107.95)
		)
		(stroke
			(width 0)
			(type default)
		)
	)
	(bus
		(pts
			(xy 259.08 92.71) (xy 259.08 90.17)
		)
		(stroke
			(width 0)
			(type default)
		)
	)
	(wire
		(pts
			(xy 284.48 99.06) (xy 287.02 99.06)
		)
		(stroke
			(width 0)
			(type default)
		)
	)
	(wire
		(pts
			(xy 323.85 149.86) (xy 344.17 149.86)
		)
		(stroke
			(width 0)
			(type default)
		)
	)
	(wire
		(pts
			(xy 114.3 144.78) (xy 121.92 144.78)
		)
		(stroke
			(width 0)
			(type default)
		)
	)
	(wire
		(pts
			(xy 99.06 48.26) (xy 99.06 49.53)
		)
		(stroke
			(width 0)
			(type default)
		)
	)
	(polyline
		(pts
			(xy 207.01 180.34) (xy 299.72 180.34)
		)
		(stroke
			(width 0)
			(type default)
		)
	)
	(wire
		(pts
			(xy 135.89 144.78) (xy 135.89 151.13)
		)
		(stroke
			(width 0)
			(type default)
		)
	)
	(wire
		(pts
			(xy 284.48 60.96) (xy 284.48 68.58)
		)
		(stroke
			(width 0)
			(type default)
		)
	)
	(wire
		(pts
			(xy 281.94 154.94) (xy 287.02 154.94)
		)
		(stroke
			(width 0)
			(type default)
		)
	)
	(wire
		(pts
			(xy 276.86 132.08) (xy 287.02 132.08)
		)
		(stroke
			(width 0)
			(type default)
		)
	)
	(wire
		(pts
			(xy 354.33 132.08) (xy 364.49 132.08)
		)
		(stroke
			(width 0)
			(type default)
		)
	)
	(bus
		(pts
			(xy 48.26 215.9) (xy 48.26 218.44)
		)
		(stroke
			(width 0)
			(type default)
		)
	)
	(wire
		(pts
			(xy 341.63 238.76) (xy 341.63 246.38)
		)
		(stroke
			(width 0)
			(type default)
		)
	)
	(wire
		(pts
			(xy 110.49 210.82) (xy 119.38 210.82)
		)
		(stroke
			(width 0)
			(type default)
		)
	)
	(wire
		(pts
			(xy 85.09 144.78) (xy 91.44 144.78)
		)
		(stroke
			(width 0)
			(type default)
		)
	)
	(wire
		(pts
			(xy 364.49 246.38) (xy 364.49 247.65)
		)
		(stroke
			(width 0)
			(type default)
		)
	)
	(wire
		(pts
			(xy 260.35 83.82) (xy 287.02 83.82)
		)
		(stroke
			(width 0)
			(type default)
		)
	)
	(wire
		(pts
			(xy 121.92 144.78) (xy 128.27 144.78)
		)
		(stroke
			(width 0)
			(type default)
		)
	)
	(wire
		(pts
			(xy 337.82 40.64) (xy 364.49 40.64)
		)
		(stroke
			(width 0)
			(type default)
		)
	)
	(wire
		(pts
			(xy 328.93 156.21) (xy 328.93 154.94)
		)
		(stroke
			(width 0)
			(type default)
		)
	)
	(bus
		(pts
			(xy 259.08 52.07) (xy 259.08 49.53)
		)
		(stroke
			(width 0)
			(type default)
		)
	)
	(wire
		(pts
			(xy 341.63 196.85) (xy 334.01 196.85)
		)
		(stroke
			(width 0)
			(type default)
		)
	)
	(wire
		(pts
			(xy 260.35 55.88) (xy 287.02 55.88)
		)
		(stroke
			(width 0)
			(type default)
		)
	)
	(wire
		(pts
			(xy 201.93 215.9) (xy 207.01 215.9)
		)
		(stroke
			(width 0)
			(type default)
		)
	)
	(wire
		(pts
			(xy 337.82 55.88) (xy 364.49 55.88)
		)
		(stroke
			(width 0)
			(type default)
		)
	)
	(wire
		(pts
			(xy 132.08 68.58) (xy 142.24 68.58)
		)
		(stroke
			(width 0)
			(type default)
		)
	)
	(wire
		(pts
			(xy 134.62 210.82) (xy 149.86 210.82)
		)
		(stroke
			(width 0)
			(type default)
		)
	)
	(wire
		(pts
			(xy 341.63 246.38) (xy 342.9 246.38)
		)
		(stroke
			(width 0)
			(type default)
		)
	)
	(wire
		(pts
			(xy 334.01 203.2) (xy 334.01 204.47)
		)
		(stroke
			(width 0)
			(type default)
		)
	)
	(wire
		(pts
			(xy 96.52 144.78) (xy 99.06 144.78)
		)
		(stroke
			(width 0)
			(type default)
		)
	)
	(wire
		(pts
			(xy 364.49 217.17) (xy 364.49 218.44)
		)
		(stroke
			(width 0)
			(type default)
		)
	)
	(wire
		(pts
			(xy 337.82 91.44) (xy 364.49 91.44)
		)
		(stroke
			(width 0)
			(type default)
		)
	)
	(wire
		(pts
			(xy 372.11 224.79) (xy 372.11 226.06)
		)
		(stroke
			(width 0)
			(type default)
		)
	)
	(wire
		(pts
			(xy 116.84 165.1) (xy 130.81 165.1)
		)
		(stroke
			(width 0)
			(type default)
		)
	)
	(wire
		(pts
			(xy 99.06 144.78) (xy 99.06 151.13)
		)
		(stroke
			(width 0)
			(type default)
		)
	)
	(wire
		(pts
			(xy 132.08 76.2) (xy 142.24 76.2)
		)
		(stroke
			(width 0)
			(type default)
		)
	)
	(bus
		(pts
			(xy 259.08 52.07) (xy 259.08 57.15)
		)
		(stroke
			(width 0)
			(type default)
		)
	)
	(wire
		(pts
			(xy 372.11 203.2) (xy 372.11 204.47)
		)
		(stroke
			(width 0)
			(type default)
		)
	)
	(wire
		(pts
			(xy 212.09 208.28) (xy 212.09 209.55)
		)
		(stroke
			(width 0)
			(type default)
		)
	)
	(wire
		(pts
			(xy 260.35 45.72) (xy 287.02 45.72)
		)
		(stroke
			(width 0)
			(type default)
		)
	)
	(wire
		(pts
			(xy 111.76 53.34) (xy 109.22 53.34)
		)
		(stroke
			(width 0)
			(type default)
		)
	)
	(wire
		(pts
			(xy 334.01 195.58) (xy 334.01 196.85)
		)
		(stroke
			(width 0)
			(type default)
		)
	)
	(wire
		(pts
			(xy 93.98 87.63) (xy 93.98 91.44)
		)
		(stroke
			(width 0)
			(type default)
		)
	)
	(wire
		(pts
			(xy 97.79 215.9) (xy 119.38 215.9)
		)
		(stroke
			(width 0)
			(type default)
		)
	)
	(wire
		(pts
			(xy 372.11 226.06) (xy 372.11 227.33)
		)
		(stroke
			(width 0)
			(type default)
		)
	)
	(wire
		(pts
			(xy 354.33 137.16) (xy 364.49 137.16)
		)
		(stroke
			(width 0)
			(type default)
		)
	)
	(wire
		(pts
			(xy 243.84 246.38) (xy 259.08 246.38)
		)
		(stroke
			(width 0)
			(type default)
		)
	)
	(wire
		(pts
			(xy 69.85 215.9) (xy 92.71 215.9)
		)
		(stroke
			(width 0)
			(type default)
		)
	)
	(wire
		(pts
			(xy 21.59 219.71) (xy 46.99 219.71)
		)
		(stroke
			(width 0)
			(type default)
		)
	)
	(wire
		(pts
			(xy 102.87 232.41) (xy 102.87 233.68)
		)
		(stroke
			(width 0)
			(type default)
		)
	)
	(wire
		(pts
			(xy 284.48 163.83) (xy 284.48 162.56)
		)
		(stroke
			(width 0)
			(type default)
		)
	)
	(wire
		(pts
			(xy 93.98 156.21) (xy 93.98 165.1)
		)
		(stroke
			(width 0)
			(type default)
		)
	)
	(bus
		(pts
			(xy 52.07 203.2) (xy 49.53 203.2)
		)
		(stroke
			(width 0)
			(type default)
		)
	)
	(bus
		(pts
			(xy 336.55 49.53) (xy 336.55 46.99)
		)
		(stroke
			(width 0)
			(type default)
		)
	)
	(wire
		(pts
			(xy 132.08 91.44) (xy 147.32 91.44)
		)
		(stroke
			(width 0)
			(type default)
		)
	)
	(wire
		(pts
			(xy 260.35 50.8) (xy 287.02 50.8)
		)
		(stroke
			(width 0)
			(type default)
		)
	)
	(wire
		(pts
			(xy 260.35 48.26) (xy 287.02 48.26)
		)
		(stroke
			(width 0)
			(type default)
		)
	)
	(bus
		(pts
			(xy 259.08 97.79) (xy 259.08 95.25)
		)
		(stroke
			(width 0)
			(type default)
		)
	)
	(wire
		(pts
			(xy 80.01 162.56) (xy 91.44 162.56)
		)
		(stroke
			(width 0)
			(type default)
		)
	)
	(polyline
		(pts
			(xy 12.7 180.34) (xy 207.01 180.34)
		)
		(stroke
			(width 0)
			(type default)
		)
	)
	(wire
		(pts
			(xy 337.82 93.98) (xy 364.49 93.98)
		)
		(stroke
			(width 0)
			(type default)
		)
	)
	(wire
		(pts
			(xy 284.48 106.68) (xy 284.48 160.02)
		)
		(stroke
			(width 0)
			(type default)
		)
	)
	(wire
		(pts
			(xy 276.86 129.54) (xy 287.02 129.54)
		)
		(stroke
			(width 0)
			(type default)
		)
	)
	(wire
		(pts
			(xy 121.92 140.97) (xy 121.92 144.78)
		)
		(stroke
			(width 0)
			(type default)
		)
	)
	(bus
		(pts
			(xy 336.55 92.71) (xy 336.55 90.17)
		)
		(stroke
			(width 0)
			(type default)
		)
	)
	(wire
		(pts
			(xy 134.62 246.38) (xy 149.86 246.38)
		)
		(stroke
			(width 0)
			(type default)
		)
	)
	(bus
		(pts
			(xy 336.55 46.99) (xy 336.55 44.45)
		)
		(stroke
			(width 0)
			(type default)
		)
	)
	(wire
		(pts
			(xy 284.48 68.58) (xy 287.02 68.58)
		)
		(stroke
			(width 0)
			(type default)
		)
	)
	(wire
		(pts
			(xy 96.52 168.91) (xy 80.01 168.91)
		)
		(stroke
			(width 0)
			(type default)
		)
	)
	(wire
		(pts
			(xy 132.08 99.06) (xy 147.32 99.06)
		)
		(stroke
			(width 0)
			(type default)
		)
	)
	(wire
		(pts
			(xy 132.08 101.6) (xy 147.32 101.6)
		)
		(stroke
			(width 0)
			(type default)
		)
	)
	(bus
		(pts
			(xy 259.08 87.63) (xy 259.08 85.09)
		)
		(stroke
			(width 0)
			(type default)
		)
	)
	(wire
		(pts
			(xy 116.84 162.56) (xy 128.27 162.56)
		)
		(stroke
			(width 0)
			(type default)
		)
	)
	(wire
		(pts
			(xy 132.08 53.34) (xy 142.24 53.34)
		)
		(stroke
			(width 0)
			(type default)
		)
	)
	(wire
		(pts
			(xy 21.59 217.17) (xy 46.99 217.17)
		)
		(stroke
			(width 0)
			(type default)
		)
	)
	(bus
		(pts
			(xy 257.81 107.95) (xy 252.73 107.95)
		)
		(stroke
			(width 0)
			(type default)
		)
	)
	(bus
		(pts
			(xy 336.55 82.55) (xy 336.55 85.09)
		)
		(stroke
			(width 0)
			(type default)
		)
	)
	(wire
		(pts
			(xy 132.08 83.82) (xy 147.32 83.82)
		)
		(stroke
			(width 0)
			(type default)
		)
	)
	(wire
		(pts
			(xy 361.95 106.68) (xy 364.49 106.68)
		)
		(stroke
			(width 0)
			(type default)
		)
	)
	(wire
		(pts
			(xy 110.49 101.6) (xy 111.76 101.6)
		)
		(stroke
			(width 0)
			(type default)
		)
	)
	(wire
		(pts
			(xy 364.49 196.85) (xy 372.11 196.85)
		)
		(stroke
			(width 0)
			(type default)
		)
	)
	(polyline
		(pts
			(xy 255.27 87.63) (xy 255.27 105.41)
		)
		(stroke
			(width 0)
			(type solid)
		)
	)
	(wire
		(pts
			(xy 337.82 96.52) (xy 364.49 96.52)
		)
		(stroke
			(width 0)
			(type default)
		)
	)
	(wire
		(pts
			(xy 361.95 99.06) (xy 361.95 106.68)
		)
		(stroke
			(width 0)
			(type default)
		)
	)
	(bus
		(pts
			(xy 336.55 59.69) (xy 336.55 60.96)
		)
		(stroke
			(width 0)
			(type default)
		)
	)
	(wire
		(pts
			(xy 337.82 83.82) (xy 364.49 83.82)
		)
		(stroke
			(width 0)
			(type default)
		)
	)
	(wire
		(pts
			(xy 361.95 68.58) (xy 364.49 68.58)
		)
		(stroke
			(width 0)
			(type default)
		)
	)
	(wire
		(pts
			(xy 130.81 156.21) (xy 130.81 165.1)
		)
		(stroke
			(width 0)
			(type default)
		)
	)
	(wire
		(pts
			(xy 256.54 132.08) (xy 271.78 132.08)
		)
		(stroke
			(width 0)
			(type default)
		)
	)
	(wire
		(pts
			(xy 93.98 80.01) (xy 93.98 82.55)
		)
		(stroke
			(width 0)
			(type default)
		)
	)
	(wire
		(pts
			(xy 337.82 58.42) (xy 364.49 58.42)
		)
		(stroke
			(width 0)
			(type default)
		)
	)
	(wire
		(pts
			(xy 363.22 212.09) (xy 381 212.09)
		)
		(stroke
			(width 0)
			(type default)
		)
	)
	(wire
		(pts
			(xy 276.86 137.16) (xy 287.02 137.16)
		)
		(stroke
			(width 0)
			(type default)
		)
	)
	(wire
		(pts
			(xy 149.86 246.38) (xy 149.86 247.65)
		)
		(stroke
			(width 0)
			(type default)
		)
	)
	(wire
		(pts
			(xy 97.79 248.92) (xy 97.79 250.19)
		)
		(stroke
			(width 0)
			(type default)
		)
	)
	(wire
		(pts
			(xy 363.22 243.84) (xy 381 243.84)
		)
		(stroke
			(width 0)
			(type default)
		)
	)
	(wire
		(pts
			(xy 284.48 160.02) (xy 284.48 162.56)
		)
		(stroke
			(width 0)
			(type default)
		)
	)
	(wire
		(pts
			(xy 341.63 226.06) (xy 334.01 226.06)
		)
		(stroke
			(width 0)
			(type default)
		)
	)
	(wire
		(pts
			(xy 344.17 149.86) (xy 359.41 149.86)
		)
		(stroke
			(width 0)
			(type default)
		)
	)
	(bus
		(pts
			(xy 66.04 64.77) (xy 66.04 67.31)
		)
		(stroke
			(width 0)
			(type default)
		)
	)
	(wire
		(pts
			(xy 259.08 219.71) (xy 259.08 220.98)
		)
		(stroke
			(width 0)
			(type default)
		)
	)
	(wire
		(pts
			(xy 135.89 215.9) (xy 135.89 220.98)
		)
		(stroke
			(width 0)
			(type default)
		)
	)
	(wire
		(pts
			(xy 260.35 93.98) (xy 287.02 93.98)
		)
		(stroke
			(width 0)
			(type default)
		)
	)
	(wire
		(pts
			(xy 363.22 241.3) (xy 381 241.3)
		)
		(stroke
			(width 0)
			(type default)
		)
	)
	(bus
		(pts
			(xy 336.55 80.01) (xy 336.55 82.55)
		)
		(stroke
			(width 0)
			(type default)
		)
	)
	(wire
		(pts
			(xy 260.35 104.14) (xy 287.02 104.14)
		)
		(stroke
			(width 0)
			(type default)
		)
	)
	(wire
		(pts
			(xy 224.79 149.86) (xy 246.38 149.86)
		)
		(stroke
			(width 0)
			(type default)
		)
	)
	(wire
		(pts
			(xy 341.63 116.84) (xy 364.49 116.84)
		)
		(stroke
			(width 0)
			(type default)
		)
	)
	(wire
		(pts
			(xy 113.03 200.66) (xy 113.03 203.2)
		)
		(stroke
			(width 0)
			(type default)
		)
	)
	(wire
		(pts
			(xy 259.08 246.38) (xy 259.08 247.65)
		)
		(stroke
			(width 0)
			(type default)
		)
	)
	(bus
		(pts
			(xy 336.55 41.91) (xy 336.55 39.37)
		)
		(stroke
			(width 0)
			(type default)
		)
	)
	(wire
		(pts
			(xy 92.71 200.66) (xy 92.71 203.2)
		)
		(stroke
			(width 0)
			(type default)
		)
	)
	(wire
		(pts
			(xy 260.35 91.44) (xy 287.02 91.44)
		)
		(stroke
			(width 0)
			(type default)
		)
	)
	(wire
		(pts
			(xy 135.89 248.92) (xy 135.89 254)
		)
		(stroke
			(width 0)
			(type default)
		)
	)
	(wire
		(pts
			(xy 93.98 144.78) (xy 93.98 151.13)
		)
		(stroke
			(width 0)
			(type default)
		)
	)
	(wire
		(pts
			(xy 337.82 104.14) (xy 364.49 104.14)
		)
		(stroke
			(width 0)
			(type default)
		)
	)
	(wire
		(pts
			(xy 260.35 101.6) (xy 287.02 101.6)
		)
		(stroke
			(width 0)
			(type default)
		)
	)
	(wire
		(pts
			(xy 93.98 144.78) (xy 96.52 144.78)
		)
		(stroke
			(width 0)
			(type default)
		)
	)
	(wire
		(pts
			(xy 259.08 252.73) (xy 259.08 254)
		)
		(stroke
			(width 0)
			(type default)
		)
	)
	(wire
		(pts
			(xy 132.08 55.88) (xy 142.24 55.88)
		)
		(stroke
			(width 0)
			(type default)
		)
	)
	(bus
		(pts
			(xy 336.55 87.63) (xy 336.55 85.09)
		)
		(stroke
			(width 0)
			(type default)
		)
	)
	(bus
		(pts
			(xy 259.08 49.53) (xy 259.08 46.99)
		)
		(stroke
			(width 0)
			(type default)
		)
	)
	(bus
		(pts
			(xy 259.08 36.83) (xy 259.08 39.37)
		)
		(stroke
			(width 0)
			(type default)
		)
	)
	(wire
		(pts
			(xy 128.27 144.78) (xy 130.81 144.78)
		)
		(stroke
			(width 0)
			(type default)
		)
	)
	(wire
		(pts
			(xy 222.25 200.66) (xy 222.25 203.2)
		)
		(stroke
			(width 0)
			(type default)
		)
	)
	(wire
		(pts
			(xy 76.2 144.78) (xy 85.09 144.78)
		)
		(stroke
			(width 0)
			(type default)
		)
	)
	(bus
		(pts
			(xy 62.23 63.5) (xy 64.77 63.5)
		)
		(stroke
			(width 0)
			(type default)
		)
	)
	(wire
		(pts
			(xy 359.41 152.4) (xy 359.41 149.86)
		)
		(stroke
			(width 0)
			(type default)
		)
	)
	(wire
		(pts
			(xy 219.71 243.84) (xy 228.6 243.84)
		)
		(stroke
			(width 0)
			(type default)
		)
	)
	(wire
		(pts
			(xy 243.84 213.36) (xy 259.08 213.36)
		)
		(stroke
			(width 0)
			(type default)
		)
	)
	(wire
		(pts
			(xy 149.86 252.73) (xy 149.86 254)
		)
		(stroke
			(width 0)
			(type default)
		)
	)
	(wire
		(pts
			(xy 259.08 213.36) (xy 259.08 214.63)
		)
		(stroke
			(width 0)
			(type default)
		)
	)
	(wire
		(pts
			(xy 260.35 86.36) (xy 287.02 86.36)
		)
		(stroke
			(width 0)
			(type default)
		)
	)
	(wire
		(pts
			(xy 284.48 53.34) (xy 284.48 60.96)
		)
		(stroke
			(width 0)
			(type default)
		)
	)
	(wire
		(pts
			(xy 21.59 222.25) (xy 46.99 222.25)
		)
		(stroke
			(width 0)
			(type default)
		)
	)
	(wire
		(pts
			(xy 260.35 96.52) (xy 287.02 96.52)
		)
		(stroke
			(width 0)
			(type default)
		)
	)
	(wire
		(pts
			(xy 219.71 201.93) (xy 219.71 210.82)
		)
		(stroke
			(width 0)
			(type default)
		)
	)
	(wire
		(pts
			(xy 85.09 96.52) (xy 111.76 96.52)
		)
		(stroke
			(width 0)
			(type default)
		)
	)
	(wire
		(pts
			(xy 344.17 149.86) (xy 344.17 156.21)
		)
		(stroke
			(width 0)
			(type default)
		)
	)
	(wire
		(pts
			(xy 342.9 238.76) (xy 341.63 238.76)
		)
		(stroke
			(width 0)
			(type default)
		)
	)
	(wire
		(pts
			(xy 316.23 212.09) (xy 342.9 212.09)
		)
		(stroke
			(width 0)
			(type default)
		)
	)
	(bus
		(pts
			(xy 336.55 44.45) (xy 336.55 41.91)
		)
		(stroke
			(width 0)
			(type default)
		)
	)
	(wire
		(pts
			(xy 110.49 201.93) (xy 102.87 201.93)
		)
		(stroke
			(width 0)
			(type default)
		)
	)
	(bus
		(pts
			(xy 259.08 90.17) (xy 259.08 87.63)
		)
		(stroke
			(width 0)
			(type default)
		)
	)
	(wire
		(pts
			(xy 113.03 213.36) (xy 113.03 231.14)
		)
		(stroke
			(width 0)
			(type default)
		)
	)
	(wire
		(pts
			(xy 354.33 134.62) (xy 364.49 134.62)
		)
		(stroke
			(width 0)
			(type default)
		)
	)
	(wire
		(pts
			(xy 266.7 149.86) (xy 266.7 156.21)
		)
		(stroke
			(width 0)
			(type default)
		)
	)
	(wire
		(pts
			(xy 287.02 152.4) (xy 281.94 152.4)
		)
		(stroke
			(width 0)
			(type default)
		)
	)
	(wire
		(pts
			(xy 281.94 154.94) (xy 281.94 157.48)
		)
		(stroke
			(width 0)
			(type default)
		)
	)
	(wire
		(pts
			(xy 222.25 231.14) (xy 222.25 246.38)
		)
		(stroke
			(width 0)
			(type default)
		)
	)
	(wire
		(pts
			(xy 251.46 156.21) (xy 251.46 154.94)
		)
		(stroke
			(width 0)
			(type default)
		)
	)
	(wire
		(pts
			(xy 260.35 38.1) (xy 287.02 38.1)
		)
		(stroke
			(width 0)
			(type default)
		)
	)
	(wire
		(pts
			(xy 260.35 81.28) (xy 287.02 81.28)
		)
		(stroke
			(width 0)
			(type default)
		)
	)
	(wire
		(pts
			(xy 219.71 210.82) (xy 228.6 210.82)
		)
		(stroke
			(width 0)
			(type default)
		)
	)
	(wire
		(pts
			(xy 110.49 110.49) (xy 110.49 109.22)
		)
		(stroke
			(width 0)
			(type default)
		)
	)
	(wire
		(pts
			(xy 334.01 137.16) (xy 349.25 137.16)
		)
		(stroke
			(width 0)
			(type default)
		)
	)
	(wire
		(pts
			(xy 341.63 209.55) (xy 341.63 217.17)
		)
		(stroke
			(width 0)
			(type default)
		)
	)
	(wire
		(pts
			(xy 361.95 60.96) (xy 361.95 68.58)
		)
		(stroke
			(width 0)
			(type default)
		)
	)
	(wire
		(pts
			(xy 207.01 248.92) (xy 207.01 250.19)
		)
		(stroke
			(width 0)
			(type default)
		)
	)
	(bus
		(pts
			(xy 336.55 59.69) (xy 336.55 57.15)
		)
		(stroke
			(width 0)
			(type default)
		)
	)
	(wire
		(pts
			(xy 361.95 60.96) (xy 364.49 60.96)
		)
		(stroke
			(width 0)
			(type default)
		)
	)
	(wire
		(pts
			(xy 260.35 88.9) (xy 287.02 88.9)
		)
		(stroke
			(width 0)
			(type default)
		)
	)
	(bus
		(pts
			(xy 48.26 205.74) (xy 48.26 208.28)
		)
		(stroke
			(width 0)
			(type default)
		)
	)
	(wire
		(pts
			(xy 363.22 246.38) (xy 364.49 246.38)
		)
		(stroke
			(width 0)
			(type default)
		)
	)
	(wire
		(pts
			(xy 337.82 78.74) (xy 364.49 78.74)
		)
		(stroke
			(width 0)
			(type default)
		)
	)
	(polyline
		(pts
			(xy 332.74 41.91) (xy 332.74 59.69)
		)
		(stroke
			(width 0)
			(type solid)
		)
	)
	(wire
		(pts
			(xy 102.87 208.28) (xy 102.87 209.55)
		)
		(stroke
			(width 0)
			(type default)
		)
	)
	(wire
		(pts
			(xy 102.87 201.93) (xy 102.87 203.2)
		)
		(stroke
			(width 0)
			(type default)
		)
	)
	(wire
		(pts
			(xy 97.79 215.9) (xy 92.71 215.9)
		)
		(stroke
			(width 0)
			(type default)
		)
	)
	(wire
		(pts
			(xy 337.82 35.56) (xy 364.49 35.56)
		)
		(stroke
			(width 0)
			(type default)
		)
	)
	(bus
		(pts
			(xy 259.08 105.41) (xy 259.08 102.87)
		)
		(stroke
			(width 0)
			(type default)
		)
	)
	(bus
		(pts
			(xy 259.08 59.69) (xy 259.08 60.96)
		)
		(stroke
			(width 0)
			(type default)
		)
	)
	(wire
		(pts
			(xy 334.01 232.41) (xy 334.01 233.68)
		)
		(stroke
			(width 0)
			(type default)
		)
	)
	(polyline
		(pts
			(xy 299.72 252.73) (xy 299.72 199.39)
		)
		(stroke
			(width 0)
			(type default)
		)
	)
	(wire
		(pts
			(xy 341.63 209.55) (xy 341.63 196.85)
		)
		(stroke
			(width 0)
			(type default)
		)
	)
	(wire
		(pts
			(xy 266.7 149.86) (xy 281.94 149.86)
		)
		(stroke
			(width 0)
			(type default)
		)
	)
	(wire
		(pts
			(xy 364.49 53.34) (xy 361.95 53.34)
		)
		(stroke
			(width 0)
			(type default)
		)
	)
	(wire
		(pts
			(xy 284.48 160.02) (xy 287.02 160.02)
		)
		(stroke
			(width 0)
			(type default)
		)
	)
	(wire
		(pts
			(xy 260.35 58.42) (xy 287.02 58.42)
		)
		(stroke
			(width 0)
			(type default)
		)
	)
	(wire
		(pts
			(xy 212.09 232.41) (xy 212.09 233.68)
		)
		(stroke
			(width 0)
			(type default)
		)
	)
	(wire
		(pts
			(xy 337.82 50.8) (xy 364.49 50.8)
		)
		(stroke
			(width 0)
			(type default)
		)
	)
	(bus
		(pts
			(xy 259.08 41.91) (xy 259.08 39.37)
		)
		(stroke
			(width 0)
			(type default)
		)
	)
	(wire
		(pts
			(xy 110.49 243.84) (xy 110.49 233.68)
		)
		(stroke
			(width 0)
			(type default)
		)
	)
	(wire
		(pts
			(xy 337.82 86.36) (xy 364.49 86.36)
		)
		(stroke
			(width 0)
			(type default)
		)
	)
	(wire
		(pts
			(xy 92.71 208.28) (xy 92.71 215.9)
		)
		(stroke
			(width 0)
			(type default)
		)
	)
	(wire
		(pts
			(xy 212.09 240.03) (xy 212.09 241.3)
		)
		(stroke
			(width 0)
			(type default)
		)
	)
	(bus
		(pts
			(xy 336.55 97.79) (xy 336.55 102.87)
		)
		(stroke
			(width 0)
			(type default)
		)
	)
	(bus
		(pts
			(xy 335.28 107.95) (xy 330.2 107.95)
		)
		(stroke
			(width 0)
			(type default)
		)
	)
	(wire
		(pts
			(xy 256.54 111.76) (xy 287.02 111.76)
		)
		(stroke
			(width 0)
			(type default)
		)
	)
	(wire
		(pts
			(xy 284.48 76.2) (xy 287.02 76.2)
		)
		(stroke
			(width 0)
			(type default)
		)
	)
	(wire
		(pts
			(xy 271.78 154.94) (xy 271.78 156.21)
		)
		(stroke
			(width 0)
			(type default)
		)
	)
	(wire
		(pts
			(xy 363.22 209.55) (xy 364.49 209.55)
		)
		(stroke
			(width 0)
			(type default)
		)
	)
	(wire
		(pts
			(xy 177.8 215.9) (xy 201.93 215.9)
		)
		(stroke
			(width 0)
			(type default)
		)
	)
	(wire
		(pts
			(xy 222.25 231.14) (xy 246.38 231.14)
		)
		(stroke
			(width 0)
			(type default)
		)
	)
	(wire
		(pts
			(xy 119.38 246.38) (xy 113.03 246.38)
		)
		(stroke
			(width 0)
			(type default)
		)
	)
	(wire
		(pts
			(xy 372.11 232.41) (xy 372.11 233.68)
		)
		(stroke
			(width 0)
			(type default)
		)
	)
	(wire
		(pts
			(xy 323.85 149.86) (xy 323.85 156.21)
		)
		(stroke
			(width 0)
			(type default)
		)
	)
	(wire
		(pts
			(xy 246.38 149.86) (xy 246.38 156.21)
		)
		(stroke
			(width 0)
			(type default)
		)
	)
	(bus
		(pts
			(xy 259.08 82.55) (xy 259.08 85.09)
		)
		(stroke
			(width 0)
			(type default)
		)
	)
	(bus
		(pts
			(xy 336.55 52.07) (xy 336.55 57.15)
		)
		(stroke
			(width 0)
			(type default)
		)
	)
	(wire
		(pts
			(xy 359.41 154.94) (xy 359.41 157.48)
		)
		(stroke
			(width 0)
			(type default)
		)
	)
	(bus
		(pts
			(xy 259.08 95.25) (xy 259.08 92.71)
		)
		(stroke
			(width 0)
			(type default)
		)
	)
	(polyline
		(pts
			(xy 207.01 12.7) (xy 207.01 180.34)
		)
		(stroke
			(width 0)
			(type default)
		)
	)
	(wire
		(pts
			(xy 21.59 212.09) (xy 46.99 212.09)
		)
		(stroke
			(width 0)
			(type default)
		)
	)
	(wire
		(pts
			(xy 21.59 209.55) (xy 46.99 209.55)
		)
		(stroke
			(width 0)
			(type default)
		)
	)
	(wire
		(pts
			(xy 85.09 134.62) (xy 85.09 135.89)
		)
		(stroke
			(width 0)
			(type default)
		)
	)
	(wire
		(pts
			(xy 341.63 111.76) (xy 364.49 111.76)
		)
		(stroke
			(width 0)
			(type default)
		)
	)
	(bus
		(pts
			(xy 259.08 105.41) (xy 259.08 106.68)
		)
		(stroke
			(width 0)
			(type default)
		)
	)
	(wire
		(pts
			(xy 364.49 238.76) (xy 364.49 226.06)
		)
		(stroke
			(width 0)
			(type default)
		)
	)
	(wire
		(pts
			(xy 284.48 106.68) (xy 287.02 106.68)
		)
		(stroke
			(width 0)
			(type default)
		)
	)
	(wire
		(pts
			(xy 256.54 116.84) (xy 287.02 116.84)
		)
		(stroke
			(width 0)
			(type default)
		)
	)
	(wire
		(pts
			(xy 302.26 149.86) (xy 323.85 149.86)
		)
		(stroke
			(width 0)
			(type default)
		)
	)
	(polyline
		(pts
			(xy 299.72 199.39) (xy 299.72 180.34)
		)
		(stroke
			(width 0)
			(type default)
		)
	)
	(wire
		(pts
			(xy 287.02 53.34) (xy 284.48 53.34)
		)
		(stroke
			(width 0)
			(type default)
		)
	)
	(wire
		(pts
			(xy 212.09 201.93) (xy 212.09 203.2)
		)
		(stroke
			(width 0)
			(type default)
		)
	)
	(wire
		(pts
			(xy 337.82 45.72) (xy 364.49 45.72)
		)
		(stroke
			(width 0)
			(type default)
		)
	)
	(wire
		(pts
			(xy 85.09 140.97) (xy 85.09 144.78)
		)
		(stroke
			(width 0)
			(type default)
		)
	)
	(bus
		(pts
			(xy 48.26 218.44) (xy 48.26 220.98)
		)
		(stroke
			(width 0)
			(type default)
		)
	)
	(wire
		(pts
			(xy 245.11 215.9) (xy 245.11 220.98)
		)
		(stroke
			(width 0)
			(type default)
		)
	)
	(wire
		(pts
			(xy 99.06 49.53) (xy 99.06 50.8)
		)
		(stroke
			(width 0)
			(type default)
		)
	)
	(wire
		(pts
			(xy 110.49 243.84) (xy 119.38 243.84)
		)
		(stroke
			(width 0)
			(type default)
		)
	)
	(wire
		(pts
			(xy 359.41 157.48) (xy 364.49 157.48)
		)
		(stroke
			(width 0)
			(type default)
		)
	)
	(bus
		(pts
			(xy 259.08 97.79) (xy 259.08 102.87)
		)
		(stroke
			(width 0)
			(type default)
		)
	)
	(wire
		(pts
			(xy 246.38 167.64) (xy 246.38 168.91)
		)
		(stroke
			(width 0)
			(type default)
		)
	)
	(wire
		(pts
			(xy 256.54 134.62) (xy 271.78 134.62)
		)
		(stroke
			(width 0)
			(type default)
		)
	)
	(wire
		(pts
			(xy 284.48 68.58) (xy 284.48 76.2)
		)
		(stroke
			(width 0)
			(type default)
		)
	)
	(wire
		(pts
			(xy 212.09 233.68) (xy 212.09 234.95)
		)
		(stroke
			(width 0)
			(type default)
		)
	)
	(wire
		(pts
			(xy 133.35 156.21) (xy 133.35 168.91)
		)
		(stroke
			(width 0)
			(type default)
		)
	)
	(wire
		(pts
			(xy 67.31 68.58) (xy 85.09 68.58)
		)
		(stroke
			(width 0)
			(type default)
		)
	)
	(wire
		(pts
			(xy 113.03 208.28) (xy 113.03 213.36)
		)
		(stroke
			(width 0)
			(type default)
		)
	)
	(wire
		(pts
			(xy 243.84 248.92) (xy 245.11 248.92)
		)
		(stroke
			(width 0)
			(type default)
		)
	)
	(wire
		(pts
			(xy 219.71 243.84) (xy 219.71 233.68)
		)
		(stroke
			(width 0)
			(type default)
		)
	)
	(wire
		(pts
			(xy 372.11 195.58) (xy 372.11 196.85)
		)
		(stroke
			(width 0)
			(type default)
		)
	)
	(wire
		(pts
			(xy 67.31 66.04) (xy 85.09 66.04)
		)
		(stroke
			(width 0)
			(type default)
		)
	)
	(wire
		(pts
			(xy 21.59 214.63) (xy 46.99 214.63)
		)
		(stroke
			(width 0)
			(type default)
		)
	)
	(wire
		(pts
			(xy 110.49 201.93) (xy 110.49 210.82)
		)
		(stroke
			(width 0)
			(type default)
		)
	)
	(wire
		(pts
			(xy 349.25 154.94) (xy 349.25 156.21)
		)
		(stroke
			(width 0)
			(type default)
		)
	)
	(bus
		(pts
			(xy 259.08 34.29) (xy 259.08 36.83)
		)
		(stroke
			(width 0)
			(type default)
		)
	)
	(wire
		(pts
			(xy 328.93 161.29) (xy 328.93 162.56)
		)
		(stroke
			(width 0)
			(type default)
		)
	)
	(wire
		(pts
			(xy 134.62 248.92) (xy 135.89 248.92)
		)
		(stroke
			(width 0)
			(type default)
		)
	)
	(bus
		(pts
			(xy 336.55 105.41) (xy 336.55 102.87)
		)
		(stroke
			(width 0)
			(type default)
		)
	)
	(wire
		(pts
			(xy 228.6 246.38) (xy 222.25 246.38)
		)
		(stroke
			(width 0)
			(type default)
		)
	)
	(wire
		(pts
			(xy 361.95 160.02) (xy 361.95 162.56)
		)
		(stroke
			(width 0)
			(type default)
		)
	)
	(wire
		(pts
			(xy 201.93 200.66) (xy 201.93 203.2)
		)
		(stroke
			(width 0)
			(type default)
		)
	)
	(wire
		(pts
			(xy 102.87 240.03) (xy 102.87 241.3)
		)
		(stroke
			(width 0)
			(type default)
		)
	)
	(bus
		(pts
			(xy 48.26 220.98) (xy 48.26 223.52)
		)
		(stroke
			(width 0)
			(type default)
		)
	)
	(bus
		(pts
			(xy 259.08 46.99) (xy 259.08 44.45)
		)
		(stroke
			(width 0)
			(type default)
		)
	)
	(wire
		(pts
			(xy 130.81 144.78) (xy 130.81 151.13)
		)
		(stroke
			(width 0)
			(type default)
		)
	)
	(wire
		(pts
			(xy 372.11 196.85) (xy 372.11 198.12)
		)
		(stroke
			(width 0)
			(type default)
		)
	)
	(polyline
		(pts
			(xy 255.27 41.91) (xy 255.27 59.69)
		)
		(stroke
			(width 0)
			(type solid)
		)
	)
	(wire
		(pts
			(xy 334.01 132.08) (xy 349.25 132.08)
		)
		(stroke
			(width 0)
			(type default)
		)
	)
	(bus
		(pts
			(xy 336.55 34.29) (xy 336.55 36.83)
		)
		(stroke
			(width 0)
			(type default)
		)
	)
	(polyline
		(pts
			(xy 332.74 87.63) (xy 332.74 105.41)
		)
		(stroke
			(width 0)
			(type solid)
		)
	)
	(bus
		(pts
			(xy 336.55 97.79) (xy 336.55 95.25)
		)
		(stroke
			(width 0)
			(type default)
		)
	)
	(bus
		(pts
			(xy 336.55 90.17) (xy 336.55 87.63)
		)
		(stroke
			(width 0)
			(type default)
		)
	)
	(wire
		(pts
			(xy 260.35 35.56) (xy 287.02 35.56)
		)
		(stroke
			(width 0)
			(type default)
		)
	)
	(bus
		(pts
			(xy 259.08 44.45) (xy 259.08 41.91)
		)
		(stroke
			(width 0)
			(type default)
		)
	)
	(wire
		(pts
			(xy 91.44 144.78) (xy 93.98 144.78)
		)
		(stroke
			(width 0)
			(type default)
		)
	)
	(wire
		(pts
			(xy 110.49 101.6) (xy 110.49 99.06)
		)
		(stroke
			(width 0)
			(type default)
		)
	)
	(wire
		(pts
			(xy 251.46 167.64) (xy 251.46 168.91)
		)
		(stroke
			(width 0)
			(type default)
		)
	)
	(bus
		(pts
			(xy 336.55 106.68) (xy 335.28 107.95)
		)
		(stroke
			(width 0)
			(type default)
		)
	)
	(wire
		(pts
			(xy 334.01 226.06) (xy 334.01 227.33)
		)
		(stroke
			(width 0)
			(type default)
		)
	)
	(wire
		(pts
			(xy 260.35 40.64) (xy 287.02 40.64)
		)
		(stroke
			(width 0)
			(type default)
		)
	)
	(wire
		(pts
			(xy 359.41 149.86) (xy 364.49 149.86)
		)
		(stroke
			(width 0)
			(type default)
		)
	)
	(wire
		(pts
			(xy 132.08 109.22) (xy 147.32 109.22)
		)
		(stroke
			(width 0)
			(type default)
		)
	)
	(wire
		(pts
			(xy 281.94 149.86) (xy 287.02 149.86)
		)
		(stroke
			(width 0)
			(type default)
		)
	)
	(wire
		(pts
			(xy 316.23 214.63) (xy 342.9 214.63)
		)
		(stroke
			(width 0)
			(type default)
		)
	)
	(polyline
		(pts
			(xy 328.93 77.47) (xy 328.93 105.41)
		)
		(stroke
			(width 0)
			(type solid)
		)
	)
	(wire
		(pts
			(xy 85.09 104.14) (xy 85.09 106.68)
		)
		(stroke
			(width 0)
			(type default)
		)
	)
	(wire
		(pts
			(xy 21.59 224.79) (xy 46.99 224.79)
		)
		(stroke
			(width 0)
			(type default)
		)
	)
	(wire
		(pts
			(xy 134.62 215.9) (xy 135.89 215.9)
		)
		(stroke
			(width 0)
			(type default)
		)
	)
	(wire
		(pts
			(xy 341.63 238.76) (xy 341.63 226.06)
		)
		(stroke
			(width 0)
			(type default)
		)
	)
	(label "VSYNC_CAM1_3V3"
		(at 381 214.63 180)
		(effects
			(font
				(size 1.27 1.27)
			)
			(justify right bottom)
		)
	)
	(label "VSYNC_CAM2_3V3"
		(at 341.63 111.76 0)
		(effects
			(font
				(size 1.27 1.27)
			)
			(justify left bottom)
		)
	)
	(label "CAM_CTRL.CSIB_FLG"
		(at 246.38 231.14 180)
		(effects
			(font
				(size 1.27 1.27)
			)
			(justify right bottom)
		)
	)
	(label "CAM_CTRL.VSYNC_CAM1"
		(at 316.23 214.63 0)
		(effects
			(font
				(size 1.27 1.27)
			)
			(justify left bottom)
		)
	)
	(label "CAM2.CSI5_D0+"
		(at 339.09 40.64 0)
		(effects
			(font
				(size 1.27 1.27)
			)
			(justify left bottom)
		)
	)
	(label "CAM1.CSI0_D0+"
		(at 261.62 96.52 0)
		(effects
			(font
				(size 1.27 1.27)
			)
			(justify left bottom)
		)
	)
	(label "CAM1.CSI0_D0-"
		(at 261.62 93.98 0)
		(effects
			(font
				(size 1.27 1.27)
			)
			(justify left bottom)
		)
	)
	(label "MUX_I2C_6_SCL"
		(at 132.08 101.6 0)
		(effects
			(font
				(size 1.27 1.27)
			)
			(justify left bottom)
		)
	)
	(label "CAM0.CSI3_D1-"
		(at 261.62 33.02 0)
		(effects
			(font
				(size 1.27 1.27)
			)
			(justify left bottom)
		)
	)
	(label "CAM_CTRL.VSYNC_CAM2"
		(at 21.59 222.25 0)
		(effects
			(font
				(size 1.27 1.27)
			)
			(justify left bottom)
		)
	)
	(label "CAM_CTRL.VSYNC_CAM2"
		(at 316.23 241.3 0)
		(effects
			(font
				(size 1.27 1.27)
			)
			(justify left bottom)
		)
	)
	(label "CSIA_3V3"
		(at 224.79 149.86 0)
		(effects
			(font
				(size 1.27 1.27)
			)
			(justify left bottom)
		)
	)
	(label "CAM1.CSI0_D1-"
		(at 261.62 88.9 0)
		(effects
			(font
				(size 1.27 1.27)
			)
			(justify left bottom)
		)
	)
	(label "SCL_CAM0"
		(at 142.24 55.88 180)
		(effects
			(font
				(size 1.27 1.27)
			)
			(justify right bottom)
		)
	)
	(label "CAM2.CSI5_D1+"
		(at 339.09 35.56 0)
		(effects
			(font
				(size 1.27 1.27)
			)
			(justify left bottom)
		)
	)
	(label "SDA_CAM1"
		(at 142.24 60.96 180)
		(effects
			(font
				(size 1.27 1.27)
			)
			(justify right bottom)
		)
	)
	(label "I2C_MUX_SDA"
		(at 110.49 66.04 180)
		(effects
			(font
				(size 1.27 1.27)
			)
			(justify right bottom)
		)
	)
	(label "CSIB_5V_ISET"
		(at 259.08 213.36 180)
		(effects
			(font
				(size 1.27 1.27)
			)
			(justify right bottom)
		)
	)
	(label "CAM_CTRL.CSIA_FLG"
		(at 134.62 231.14 180)
		(effects
			(font
				(size 1.27 1.27)
			)
			(justify right bottom)
		)
	)
	(label "CAM_CTRL.VSYNC_CAM1"
		(at 21.59 219.71 0)
		(effects
			(font
				(size 1.27 1.27)
			)
			(justify left bottom)
		)
	)
	(label "CAM_CTRL.CSIB_FLG"
		(at 21.59 214.63 0)
		(effects
			(font
				(size 1.27 1.27)
			)
			(justify left bottom)
		)
	)
	(label "SCL_CAM2"
		(at 334.01 132.08 0)
		(effects
			(font
				(size 1.27 1.27)
			)
			(justify left bottom)
		)
	)
	(label "CAM_CTRL.CSIB_PEN"
		(at 177.8 215.9 0)
		(effects
			(font
				(size 1.27 1.27)
			)
			(justify left bottom)
		)
	)
	(label "CAM0.CSI3_D0-"
		(at 261.62 38.1 0)
		(effects
			(font
				(size 1.27 1.27)
			)
			(justify left bottom)
		)
	)
	(label "CAM_CTRL.CSIA_FLG"
		(at 21.59 212.09 0)
		(effects
			(font
				(size 1.27 1.27)
			)
			(justify left bottom)
		)
	)
	(label "CSIB_3V3_ISET"
		(at 259.08 246.38 180)
		(effects
			(font
				(size 1.27 1.27)
			)
			(justify right bottom)
		)
	)
	(label "CSIB_5V"
		(at 302.26 154.94 0)
		(effects
			(font
				(size 1.27 1.27)
			)
			(justify left bottom)
		)
	)
	(label "CAM0.CSI2_D1-"
		(at 261.62 43.18 0)
		(effects
			(font
				(size 1.27 1.27)
			)
			(justify left bottom)
		)
	)
	(label "SCL_CAM2"
		(at 142.24 71.12 180)
		(effects
			(font
				(size 1.27 1.27)
			)
			(justify right bottom)
		)
	)
	(label "MUX_I2C_4_SCL"
		(at 132.08 86.36 0)
		(effects
			(font
				(size 1.27 1.27)
			)
			(justify left bottom)
		)
	)
	(label "CAM_CTRL.CSIB_PEN"
		(at 21.59 209.55 0)
		(effects
			(font
				(size 1.27 1.27)
			)
			(justify left bottom)
		)
	)
	(label "VSYNC_CAM0_3V3"
		(at 381 212.09 180)
		(effects
			(font
				(size 1.27 1.27)
			)
			(justify right bottom)
		)
	)
	(label "VSYNC_CAM3_3V3"
		(at 381 243.84 180)
		(effects
			(font
				(size 1.27 1.27)
			)
			(justify right bottom)
		)
	)
	(label "CAM3.CSI6_D1+"
		(at 339.09 91.44 0)
		(effects
			(font
				(size 1.27 1.27)
			)
			(justify left bottom)
		)
	)
	(label "CAM_CTRL.VSYNC_CAM0"
		(at 21.59 217.17 0)
		(effects
			(font
				(size 1.27 1.27)
			)
			(justify left bottom)
		)
	)
	(label "CAM3.CSI6_CLK-"
		(at 339.09 101.6 0)
		(effects
			(font
				(size 1.27 1.27)
			)
			(justify left bottom)
		)
	)
	(label "CAM2.CSI4_D0+"
		(at 339.09 50.8 0)
		(effects
			(font
				(size 1.27 1.27)
			)
			(justify left bottom)
		)
	)
	(label "CSIA_I2C_VCC"
		(at 99.06 144.78 180)
		(effects
			(font
				(size 1.27 1.27)
			)
			(justify right bottom)
		)
	)
	(label "SDA_CAM1"
		(at 80.01 165.1 0)
		(effects
			(font
				(size 1.27 1.27)
			)
			(justify left bottom)
		)
	)
	(label "CAM1.CSI0_CLK-"
		(at 261.62 101.6 0)
		(effects
			(font
				(size 1.27 1.27)
			)
			(justify left bottom)
		)
	)
	(label "CAM0.CSI3_D0+"
		(at 261.62 40.64 0)
		(effects
			(font
				(size 1.27 1.27)
			)
			(justify left bottom)
		)
	)
	(label "CSIA_3V3"
		(at 149.86 243.84 180)
		(effects
			(font
				(size 1.27 1.27)
			)
			(justify right bottom)
		)
	)
	(label "CAM_CTRL.CSIA_PEN"
		(at 21.59 207.01 0)
		(effects
			(font
				(size 1.27 1.27)
			)
			(justify left bottom)
		)
	)
	(label "SCL_CAM0"
		(at 256.54 132.08 0)
		(effects
			(font
				(size 1.27 1.27)
			)
			(justify left bottom)
		)
	)
	(label "CAM0.CSI2_D0+"
		(at 261.62 50.8 0)
		(effects
			(font
				(size 1.27 1.27)
			)
			(justify left bottom)
		)
	)
	(label "CSIA_5V_ISET"
		(at 149.86 213.36 180)
		(effects
			(font
				(size 1.27 1.27)
			)
			(justify right bottom)
		)
	)
	(label "MUX_I2C_6_SDA"
		(at 132.08 99.06 0)
		(effects
			(font
				(size 1.27 1.27)
			)
			(justify left bottom)
		)
	)
	(label "SCL_CAM3"
		(at 142.24 78.74 180)
		(effects
			(font
				(size 1.27 1.27)
			)
			(justify right bottom)
		)
	)
	(label "SCL_CAM3"
		(at 334.01 137.16 0)
		(effects
			(font
				(size 1.27 1.27)
			)
			(justify left bottom)
		)
	)
	(label "CAM3.CSI6_D0-"
		(at 339.09 93.98 0)
		(effects
			(font
				(size 1.27 1.27)
			)
			(justify left bottom)
		)
	)
	(label "CAM3.CSI7_D1-"
		(at 339.09 78.74 0)
		(effects
			(font
				(size 1.27 1.27)
			)
			(justify left bottom)
		)
	)
	(label "MUX_I2C_7_SDA"
		(at 132.08 106.68 0)
		(effects
			(font
				(size 1.27 1.27)
			)
			(justify left bottom)
		)
	)
	(label "CAM0.CSI3_D1+"
		(at 261.62 35.56 0)
		(effects
			(font
				(size 1.27 1.27)
			)
			(justify left bottom)
		)
	)
	(label "SCL_CAM3"
		(at 116.84 171.45 0)
		(effects
			(font
				(size 1.27 1.27)
			)
			(justify left bottom)
		)
	)
	(label "SCL_CAM1"
		(at 142.24 63.5 180)
		(effects
			(font
				(size 1.27 1.27)
			)
			(justify right bottom)
		)
	)
	(label "SDA_CAM3"
		(at 334.01 134.62 0)
		(effects
			(font
				(size 1.27 1.27)
			)
			(justify left bottom)
		)
	)
	(label "MUX_I2C_4_SDA"
		(at 132.08 83.82 0)
		(effects
			(font
				(size 1.27 1.27)
			)
			(justify left bottom)
		)
	)
	(label "CSIA_3V3_ISET"
		(at 149.86 246.38 180)
		(effects
			(font
				(size 1.27 1.27)
			)
			(justify right bottom)
		)
	)
	(label "I2C_{CAM}.SDA"
		(at 68.58 66.04 0)
		(effects
			(font
				(size 1.27 1.27)
			)
			(justify left bottom)
		)
	)
	(label "CAM0.CSI2_D1+"
		(at 261.62 45.72 0)
		(effects
			(font
				(size 1.27 1.27)
			)
			(justify left bottom)
		)
	)
	(label "I2C_MUX_A0"
		(at 96.52 96.52 0)
		(effects
			(font
				(size 1.27 1.27)
			)
			(justify left bottom)
		)
	)
	(label "CAM1.CSI1_D0+"
		(at 261.62 86.36 0)
		(effects
			(font
				(size 1.27 1.27)
			)
			(justify left bottom)
		)
	)
	(label "CAM1.CSI1_D1-"
		(at 261.62 78.74 0)
		(effects
			(font
				(size 1.27 1.27)
			)
			(justify left bottom)
		)
	)
	(label "CAM1.CSI0_CLK+"
		(at 261.62 104.14 0)
		(effects
			(font
				(size 1.27 1.27)
			)
			(justify left bottom)
		)
	)
	(label "CAM_CTRL.VSYNC_CAM3"
		(at 21.59 224.79 0)
		(effects
			(font
				(size 1.27 1.27)
			)
			(justify left bottom)
		)
	)
	(label "VSYNC_CAM1_3V3"
		(at 256.54 116.84 0)
		(effects
			(font
				(size 1.27 1.27)
			)
			(justify left bottom)
		)
	)
	(label "CAM3.CSI7_D0+"
		(at 339.09 86.36 0)
		(effects
			(font
				(size 1.27 1.27)
			)
			(justify left bottom)
		)
	)
	(label "CAM2.CSI4_D0-"
		(at 339.09 48.26 0)
		(effects
			(font
				(size 1.27 1.27)
			)
			(justify left bottom)
		)
	)
	(label "SDA_CAM2"
		(at 116.84 162.56 0)
		(effects
			(font
				(size 1.27 1.27)
			)
			(justify left bottom)
		)
	)
	(label "SCL_CAM2"
		(at 116.84 165.1 0)
		(effects
			(font
				(size 1.27 1.27)
			)
			(justify left bottom)
		)
	)
	(label "SDA_CAM3"
		(at 142.24 76.2 180)
		(effects
			(font
				(size 1.27 1.27)
			)
			(justify right bottom)
		)
	)
	(label "SDA_CAM2"
		(at 334.01 129.54 0)
		(effects
			(font
				(size 1.27 1.27)
			)
			(justify left bottom)
		)
	)
	(label "CAM0.CSI2_D0-"
		(at 261.62 48.26 0)
		(effects
			(font
				(size 1.27 1.27)
			)
			(justify left bottom)
		)
	)
	(label "SDA_CAM1"
		(at 256.54 134.62 0)
		(effects
			(font
				(size 1.27 1.27)
			)
			(justify left bottom)
		)
	)
	(label "CAM3.CSI6_D1-"
		(at 339.09 88.9 0)
		(effects
			(font
				(size 1.27 1.27)
			)
			(justify left bottom)
		)
	)
	(label "CSIB_5V"
		(at 259.08 210.82 180)
		(effects
			(font
				(size 1.27 1.27)
			)
			(justify right bottom)
		)
	)
	(label "CAM_CTRL.VSYNC_CAM0"
		(at 316.23 212.09 0)
		(effects
			(font
				(size 1.27 1.27)
			)
			(justify left bottom)
		)
	)
	(label "CAM3.CSI7_D0-"
		(at 339.09 83.82 0)
		(effects
			(font
				(size 1.27 1.27)
			)
			(justify left bottom)
		)
	)
	(label "VSYNC_CAM0_3V3"
		(at 256.54 111.76 0)
		(effects
			(font
				(size 1.27 1.27)
			)
			(justify left bottom)
		)
	)
	(label "VSYNC_CAM2_3V3"
		(at 381 241.3 180)
		(effects
			(font
				(size 1.27 1.27)
			)
			(justify right bottom)
		)
	)
	(label "CSIB_I2C_VCC"
		(at 135.89 144.78 180)
		(effects
			(font
				(size 1.27 1.27)
			)
			(justify right bottom)
		)
	)
	(label "CAM1.CSI1_D0-"
		(at 261.62 83.82 0)
		(effects
			(font
				(size 1.27 1.27)
			)
			(justify left bottom)
		)
	)
	(label "CAM0.CSI2_CLK+"
		(at 261.62 58.42 0)
		(effects
			(font
				(size 1.27 1.27)
			)
			(justify left bottom)
		)
	)
	(label "VSYNC_CAM3_3V3"
		(at 341.63 116.84 0)
		(effects
			(font
				(size 1.27 1.27)
			)
			(justify left bottom)
		)
	)
	(label "SCL_CAM1"
		(at 80.01 162.56 0)
		(effects
			(font
				(size 1.27 1.27)
			)
			(justify left bottom)
		)
	)
	(label "SCL_CAM1"
		(at 256.54 137.16 0)
		(effects
			(font
				(size 1.27 1.27)
			)
			(justify left bottom)
		)
	)
	(label "SDA_CAM2"
		(at 142.24 68.58 180)
		(effects
			(font
				(size 1.27 1.27)
			)
			(justify right bottom)
		)
	)
	(label "CAM0.CSI2_CLK-"
		(at 261.62 55.88 0)
		(effects
			(font
				(size 1.27 1.27)
			)
			(justify left bottom)
		)
	)
	(label "CAM1.CSI1_D1+"
		(at 261.62 81.28 0)
		(effects
			(font
				(size 1.27 1.27)
			)
			(justify left bottom)
		)
	)
	(label "SDA_CAM0"
		(at 142.24 53.34 180)
		(effects
			(font
				(size 1.27 1.27)
			)
			(justify right bottom)
		)
	)
	(label "MUX_I2C_5_SCL"
		(at 132.08 93.98 0)
		(effects
			(font
				(size 1.27 1.27)
			)
			(justify left bottom)
		)
	)
	(label "MUX_I2C_5_SDA"
		(at 132.08 91.44 0)
		(effects
			(font
				(size 1.27 1.27)
			)
			(justify left bottom)
		)
	)
	(label "I2C_MUX_RESET"
		(at 96.52 91.44 0)
		(effects
			(font
				(size 1.27 1.27)
			)
			(justify left bottom)
		)
	)
	(label "CAM2.CSI4_CLK-"
		(at 339.09 55.88 0)
		(effects
			(font
				(size 1.27 1.27)
			)
			(justify left bottom)
		)
	)
	(label "CAM3.CSI6_CLK+"
		(at 339.09 104.14 0)
		(effects
			(font
				(size 1.27 1.27)
			)
			(justify left bottom)
		)
	)
	(label "CAM2.CSI5_D1-"
		(at 339.09 33.02 0)
		(effects
			(font
				(size 1.27 1.27)
			)
			(justify left bottom)
		)
	)
	(label "CSIB_3V3"
		(at 302.26 149.86 0)
		(effects
			(font
				(size 1.27 1.27)
			)
			(justify left bottom)
		)
	)
	(label "CSIA_5V"
		(at 224.79 154.94 0)
		(effects
			(font
				(size 1.27 1.27)
			)
			(justify left bottom)
		)
	)
	(label "SDA_CAM0"
		(at 80.01 171.45 0)
		(effects
			(font
				(size 1.27 1.27)
			)
			(justify left bottom)
		)
	)
	(label "CSIB_3V3"
		(at 259.08 243.84 180)
		(effects
			(font
				(size 1.27 1.27)
			)
			(justify right bottom)
		)
	)
	(label "SDA_CAM0"
		(at 256.54 129.54 0)
		(effects
			(font
				(size 1.27 1.27)
			)
			(justify left bottom)
		)
	)
	(label "CAM_CTRL.CSIA_PEN"
		(at 69.85 215.9 0)
		(effects
			(font
				(size 1.27 1.27)
			)
			(justify left bottom)
		)
	)
	(label "CAM3.CSI6_D0+"
		(at 339.09 96.52 0)
		(effects
			(font
				(size 1.27 1.27)
			)
			(justify left bottom)
		)
	)
	(label "I2C_{CAM}.SCL"
		(at 68.58 68.58 0)
		(effects
			(font
				(size 1.27 1.27)
			)
			(justify left bottom)
		)
	)
	(label "CAM2.CSI4_D1+"
		(at 339.09 45.72 0)
		(effects
			(font
				(size 1.27 1.27)
			)
			(justify left bottom)
		)
	)
	(label "CAM2.CSI4_D1-"
		(at 339.09 43.18 0)
		(effects
			(font
				(size 1.27 1.27)
			)
			(justify left bottom)
		)
	)
	(label "CSIA_5V"
		(at 149.86 210.82 180)
		(effects
			(font
				(size 1.27 1.27)
			)
			(justify right bottom)
		)
	)
	(label "SCL_CAM0"
		(at 80.01 168.91 0)
		(effects
			(font
				(size 1.27 1.27)
			)
			(justify left bottom)
		)
	)
	(label "CAM3.CSI7_D1+"
		(at 339.09 81.28 0)
		(effects
			(font
				(size 1.27 1.27)
			)
			(justify left bottom)
		)
	)
	(label "I2C_MUX_SCL"
		(at 110.49 68.58 180)
		(effects
			(font
				(size 1.27 1.27)
			)
			(justify right bottom)
		)
	)
	(label "MUX_I2C_7_SCL"
		(at 132.08 109.22 0)
		(effects
			(font
				(size 1.27 1.27)
			)
			(justify left bottom)
		)
	)
	(label "CAM1.CSI0_D1+"
		(at 261.62 91.44 0)
		(effects
			(font
				(size 1.27 1.27)
			)
			(justify left bottom)
		)
	)
	(label "CAM_CTRL.VSYNC_CAM3"
		(at 316.23 243.84 0)
		(effects
			(font
				(size 1.27 1.27)
			)
			(justify left bottom)
		)
	)
	(label "SDA_CAM3"
		(at 116.84 168.91 0)
		(effects
			(font
				(size 1.27 1.27)
			)
			(justify left bottom)
		)
	)
	(label "CAM2.CSI4_CLK+"
		(at 339.09 58.42 0)
		(effects
			(font
				(size 1.27 1.27)
			)
			(justify left bottom)
		)
	)
	(label "CAM2.CSI5_D0-"
		(at 339.09 38.1 0)
		(effects
			(font
				(size 1.27 1.27)
			)
			(justify left bottom)
		)
	)
	(hierarchical_label "I2C_{CAM}{I2C}"
		(shape bidirectional)
		(at 62.23 63.5 180)
		(effects
			(font
				(size 1.27 1.27)
			)
			(justify right)
		)
	)
	(hierarchical_label "CAM2{CSI}"
		(shape output)
		(at 330.2 62.23 180)
		(effects
			(font
				(size 1.27 1.27)
			)
			(justify right)
		)
	)
	(hierarchical_label "CAM_CTRL{CAM_CTRL}"
		(shape bidirectional)
		(at 52.07 203.2 0)
		(effects
			(font
				(size 1.27 1.27)
			)
			(justify left)
		)
	)
	(hierarchical_label "CAM3{CSI}"
		(shape output)
		(at 330.2 107.95 180)
		(effects
			(font
				(size 1.27 1.27)
			)
			(justify right)
		)
	)
	(hierarchical_label "CAM1{CSI}"
		(shape output)
		(at 252.73 107.95 180)
		(effects
			(font
				(size 1.27 1.27)
			)
			(justify right)
		)
	)
	(hierarchical_label "CAM0{CSI}"
		(shape output)
		(at 252.73 62.23 180)
		(effects
			(font
				(size 1.27 1.27)
			)
			(justify right)
		)
	)
	(rule_area
		(polyline
			(pts
				(xy 279.4 105.41) (xy 260.35 105.41) (xy 260.35 30.48) (xy 279.4 30.48)
			)
			(stroke
				(width 0)
				(type dash)
			)
			(fill
				(type none)
			)
		)
	)
	(rule_area
		(polyline
			(pts
				(xy 356.87 105.41) (xy 337.82 105.41) (xy 337.82 30.48) (xy 356.87 30.48)
			)
			(stroke
				(width 0)
				(type dash)
			)
			(fill
				(type none)
			)
		)
	)
	(netclass_flag ""
		(length 2.54)
		(shape round)
		(at 337.82 30.48 0)
		(effects
			(font
				(size 1.27 1.27)
			)
			(justify left bottom)
		)
		(property "Netclass" "90Ohm-diff_CSI"
			(at 337.566 25.908 0)
			(effects
				(font
					(size 1.27 1.27)
				)
				(justify left)
			)
		)
		(property "Component Class" ""
			(at 175.26 -11.43 0)
			(effects
				(font
					(size 1.27 1.27)
					(italic yes)
				)
				(justify right)
			)
		)
	)
	(netclass_flag ""
		(length 2.54)
		(shape round)
		(at 260.35 30.48 0)
		(effects
			(font
				(size 1.27 1.27)
			)
			(justify left bottom)
		)
		(property "Netclass" "90Ohm-diff_CSI"
			(at 260.096 25.908 0)
			(effects
				(font
					(size 1.27 1.27)
				)
				(justify left)
			)
		)
		(property "Component Class" ""
			(at 97.79 -11.43 0)
			(effects
				(font
					(size 1.27 1.27)
					(italic yes)
				)
				(justify right)
			)
		)
	)
	(symbol
		(lib_id "antmicroResistors0402:R_2k2_0402")
		(at 130.81 151.13 270)
		(unit 1)
		(exclude_from_sim no)
		(in_bom yes)
		(on_board yes)
		(dnp no)
		(property "Reference" "R392"
			(at 129.794 146.558 0)
			(effects
				(font
					(size 1.27 1.27)
					(thickness 0.15)
				)
				(justify left)
			)
		)
		(property "Value" "R_2k2_0402"
			(at 118.11 171.45 0)
			(effects
				(font
					(size 1.27 1.27)
					(thickness 0.15)
				)
				(justify left bottom)
				(hide yes)
			)
		)
		(property "Footprint" "antmicro-footprints:R_0402_1005Metric"
			(at 115.57 171.45 0)
			(effects
				(font
					(size 1.27 1.27)
					(thickness 0.15)
				)
				(justify left bottom)
				(hide yes)
			)
		)
		(property "Datasheet" "https://www.bourns.com/docs/product-datasheets/cr.pdf"
			(at 113.03 171.45 0)
			(effects
				(font
					(size 1.27 1.27)
					(thickness 0.15)
				)
				(justify left bottom)
				(hide yes)
			)
		)
		(property "Description" "SMD Chip Resistor, 2.2 kohm, ± 1%, 62.5 mW, 0402 [1005 Metric], Thick Film, General Purpose"
			(at 100.33 171.45 0)
			(effects
				(font
					(size 1.27 1.27)
				)
				(justify left bottom)
				(hide yes)
			)
		)
		(property "MPN" "CR0402-FX-2201GLF"
			(at 110.49 171.45 0)
			(effects
				(font
					(size 1.27 1.27)
					(thickness 0.15)
				)
				(justify left bottom)
				(hide yes)
			)
		)
		(property "Manufacturer" "Bourns"
			(at 107.95 171.45 0)
			(effects
				(font
					(size 1.27 1.27)
					(thickness 0.15)
				)
				(justify left bottom)
				(hide yes)
			)
		)
		(property "License" "Apache-2.0"
			(at 105.41 171.45 0)
			(effects
				(font
					(size 1.27 1.27)
					(thickness 0.15)
				)
				(justify left bottom)
				(hide yes)
			)
		)
		(property "Author" "Antmicro"
			(at 102.87 171.45 0)
			(effects
				(font
					(size 1.27 1.27)
					(thickness 0.15)
				)
				(justify left bottom)
				(hide yes)
			)
		)
		(property "Val" "2k2"
			(at 129.794 155.702 0)
			(effects
				(font
					(size 1.27 1.27)
					(thickness 0.15)
				)
				(justify left)
			)
		)
		(property "Tolerance" "1%"
			(at 120.65 171.45 0)
			(effects
				(font
					(size 1.27 1.27)
				)
				(justify left bottom)
				(hide yes)
			)
		)
		(pin "1"
		)
		(pin "2"
		)
		(instances
			(project "jetson-agx-thor-baseboard"
				(path ""
					(reference "R392")
					(unit 1)
				)
			)
		)
	)
	(symbol
		(lib_id "antmicropower:+1V8")
		(at 334.01 224.79 0)
		(unit 1)
		(exclude_from_sim no)
		(in_bom yes)
		(on_board yes)
		(dnp no)
		(property "Reference" "#PWR0328"
			(at 334.01 228.6 0)
			(effects
				(font
					(size 1.27 1.27)
				)
				(justify left bottom)
				(hide yes)
			)
		)
		(property "Value" "+1V8"
			(at 330.835 220.98 0)
			(effects
				(font
					(size 1.27 1.27)
					(thickness 0.15)
				)
				(justify left)
			)
		)
		(property "Footprint" ""
			(at 349.25 232.41 0)
			(effects
				(font
					(size 1.27 1.27)
					(thickness 0.15)
				)
				(justify left bottom)
				(hide yes)
			)
		)
		(property "Datasheet" ""
			(at 349.25 234.95 0)
			(effects
				(font
					(size 1.27 1.27)
					(thickness 0.15)
				)
				(justify left bottom)
				(hide yes)
			)
		)
		(property "Description" ""
			(at 334.01 224.79 0)
			(effects
				(font
					(size 1.27 1.27)
				)
				(hide yes)
			)
		)
		(property "Author" "Antmicro"
			(at 349.25 229.87 0)
			(effects
				(font
					(size 1.27 1.27)
					(thickness 0.15)
				)
				(justify left bottom)
				(hide yes)
			)
		)
		(property "License" "Apache-2.0"
			(at 349.25 232.41 0)
			(effects
				(font
					(size 1.27 1.27)
					(thickness 0.15)
				)
				(justify left bottom)
				(hide yes)
			)
		)
		(pin "1"
		)
		(instances
			(project "jetson-agx-thor-baseboard"
				(path ""
					(reference "#PWR0328")
					(unit 1)
				)
			)
		)
	)
	(symbol
		(lib_id "antmicroCapacitors0402:C_100n_0402")
		(at 102.87 203.2 90)
		(mirror x)
		(unit 1)
		(exclude_from_sim no)
		(in_bom yes)
		(on_board yes)
		(dnp no)
		(property "Reference" "C156"
			(at 104.775 204.47 90)
			(effects
				(font
					(size 1.27 1.27)
				)
				(justify right)
			)
		)
		(property "Value" "C_100n_0402"
			(at 113.03 223.52 0)
			(effects
				(font
					(size 1.27 1.27)
					(thickness 0.15)
				)
				(justify left bottom)
				(hide yes)
			)
		)
		(property "Footprint" "antmicro-footprints:C_0402_1005Metric"
			(at 115.57 223.52 0)
			(effects
				(font
					(size 1.27 1.27)
					(thickness 0.15)
				)
				(justify left bottom)
				(hide yes)
			)
		)
		(property "Datasheet" "https://www.murata.com/products/productdetail?partno=GRM155R61H104KE14%23"
			(at 118.11 223.52 0)
			(effects
				(font
					(size 1.27 1.27)
					(thickness 0.15)
				)
				(justify left bottom)
				(hide yes)
			)
		)
		(property "Description" "SMD Multilayer Ceramic Capacitor, 0.1 µF, 50 V, 0402 [1005 Metric], ± 10%, X5R, GRM Series"
			(at 102.87 203.2 0)
			(effects
				(font
					(size 1.27 1.27)
				)
				(hide yes)
			)
		)
		(property "Manufacturer" "Murata"
			(at 123.19 223.52 0)
			(effects
				(font
					(size 1.27 1.27)
					(thickness 0.15)
				)
				(justify left bottom)
				(hide yes)
			)
		)
		(property "MPN" "GRM155R61H104KE14D"
			(at 120.65 223.52 0)
			(effects
				(font
					(size 1.27 1.27)
					(thickness 0.15)
				)
				(justify left bottom)
				(hide yes)
			)
		)
		(property "Val" "100n"
			(at 104.775 207.01 90)
			(effects
				(font
					(size 1.27 1.27)
					(thickness 0.15)
				)
				(justify right)
			)
		)
		(property "License" "Apache-2.0"
			(at 125.73 223.52 0)
			(effects
				(font
					(size 1.27 1.27)
					(thickness 0.15)
				)
				(justify left bottom)
				(hide yes)
			)
		)
		(property "Author" "Antmicro"
			(at 128.27 223.52 0)
			(effects
				(font
					(size 1.27 1.27)
					(thickness 0.15)
				)
				(justify left bottom)
				(hide yes)
			)
		)
		(property "Voltage" "50V"
			(at 130.81 223.52 0)
			(effects
				(font
					(size 1.27 1.27)
				)
				(justify left bottom)
				(hide yes)
			)
		)
		(property "Dielectric" "X5R"
			(at 133.35 223.52 0)
			(effects
				(font
					(size 1.27 1.27)
				)
				(justify left bottom)
				(hide yes)
			)
		)
		(pin "1"
		)
		(pin "2"
		)
		(instances
			(project "jetson-agx-thor-baseboard"
				(path ""
					(reference "C156")
					(unit 1)
				)
			)
		)
	)
	(symbol
		(lib_id "antmicroCapacitors0402:C_100n_0402")
		(at 334.01 203.2 270)
		(mirror x)
		(unit 1)
		(exclude_from_sim no)
		(in_bom yes)
		(on_board yes)
		(dnp no)
		(property "Reference" "C162"
			(at 332.105 199.39 90)
			(effects
				(font
					(size 1.27 1.27)
				)
				(justify right)
			)
		)
		(property "Value" "C_100n_0402"
			(at 323.85 182.88 0)
			(effects
				(font
					(size 1.27 1.27)
					(thickness 0.15)
				)
				(justify left bottom)
				(hide yes)
			)
		)
		(property "Footprint" "antmicro-footprints:C_0402_1005Metric"
			(at 321.31 182.88 0)
			(effects
				(font
					(size 1.27 1.27)
					(thickness 0.15)
				)
				(justify left bottom)
				(hide yes)
			)
		)
		(property "Datasheet" "https://www.murata.com/products/productdetail?partno=GRM155R61H104KE14%23"
			(at 318.77 182.88 0)
			(effects
				(font
					(size 1.27 1.27)
					(thickness 0.15)
				)
				(justify left bottom)
				(hide yes)
			)
		)
		(property "Description" "SMD Multilayer Ceramic Capacitor, 0.1 µF, 50 V, 0402 [1005 Metric], ± 10%, X5R, GRM Series"
			(at 334.01 203.2 0)
			(effects
				(font
					(size 1.27 1.27)
				)
				(hide yes)
			)
		)
		(property "Manufacturer" "Murata"
			(at 313.69 182.88 0)
			(effects
				(font
					(size 1.27 1.27)
					(thickness 0.15)
				)
				(justify left bottom)
				(hide yes)
			)
		)
		(property "MPN" "GRM155R61H104KE14D"
			(at 316.23 182.88 0)
			(effects
				(font
					(size 1.27 1.27)
					(thickness 0.15)
				)
				(justify left bottom)
				(hide yes)
			)
		)
		(property "Val" "100n"
			(at 332.105 201.93 90)
			(effects
				(font
					(size 1.27 1.27)
					(thickness 0.15)
				)
				(justify right)
			)
		)
		(property "License" "Apache-2.0"
			(at 311.15 182.88 0)
			(effects
				(font
					(size 1.27 1.27)
					(thickness 0.15)
				)
				(justify left bottom)
				(hide yes)
			)
		)
		(property "Author" "Antmicro"
			(at 308.61 182.88 0)
			(effects
				(font
					(size 1.27 1.27)
					(thickness 0.15)
				)
				(justify left bottom)
				(hide yes)
			)
		)
		(property "Voltage" "50V"
			(at 306.07 182.88 0)
			(effects
				(font
					(size 1.27 1.27)
				)
				(justify left bottom)
				(hide yes)
			)
		)
		(property "Dielectric" "X5R"
			(at 303.53 182.88 0)
			(effects
				(font
					(size 1.27 1.27)
				)
				(justify left bottom)
				(hide yes)
			)
		)
		(pin "1"
		)
		(pin "2"
		)
		(instances
			(project "jetson-agx-thor-baseboard"
				(path ""
					(reference "C162")
					(unit 1)
				)
			)
		)
	)
	(symbol
		(lib_id "antmicroLogicSignalSwitchesMultiplexersDecoders:PI4MSD5V9548AZDEX")
		(at 111.76 53.34 0)
		(unit 1)
		(exclude_from_sim no)
		(in_bom yes)
		(on_board yes)
		(dnp no)
		(property "Reference" "U43"
			(at 121.92 46.99 0)
			(effects
				(font
					(size 1.27 1.27)
				)
			)
		)
		(property "Value" "PI4MSD5V9548AZDEX"
			(at 147.32 58.42 0)
			(effects
				(font
					(size 1.27 1.27)
					(thickness 0.15)
				)
				(justify left bottom)
				(hide yes)
			)
		)
		(property "Footprint" "antmicro-footprints:VQFN-24-1EP_3.8x3.8x1.0mm_P0.5mm"
			(at 147.32 60.96 0)
			(effects
				(font
					(size 1.27 1.27)
					(thickness 0.15)
				)
				(justify left bottom)
				(hide yes)
			)
		)
		(property "Datasheet" "https://www.mouser.com/datasheet/2/115/DIOD_S_A0003139195_1-2542233.pdf"
			(at 147.32 63.5 0)
			(effects
				(font
					(size 1.27 1.27)
					(thickness 0.15)
				)
				(justify left bottom)
				(hide yes)
			)
		)
		(property "Description" "Logic signal switch/multiplexer/decoder"
			(at 111.76 53.34 0)
			(effects
				(font
					(size 1.27 1.27)
				)
				(hide yes)
			)
		)
		(property "Manufacturer" "Diodes Incorporated"
			(at 147.32 66.04 0)
			(effects
				(font
					(size 1.27 1.27)
					(thickness 0.15)
				)
				(justify left bottom)
				(hide yes)
			)
		)
		(property "MPN" "PI4MSD5V9548AZDEX"
			(at 121.92 49.53 0)
			(effects
				(font
					(size 1.27 1.27)
					(thickness 0.15)
				)
			)
		)
		(property "Author" "Antmicro"
			(at 147.32 71.12 0)
			(effects
				(font
					(size 1.27 1.27)
					(thickness 0.15)
				)
				(justify left bottom)
				(hide yes)
			)
		)
		(property "License" "Apache-2.0"
			(at 147.32 73.66 0)
			(effects
				(font
					(size 1.27 1.27)
					(thickness 0.15)
				)
				(justify left bottom)
				(hide yes)
			)
		)
		(pin "1"
		)
		(pin "10"
		)
		(pin "11"
		)
		(pin "12"
		)
		(pin "13"
		)
		(pin "14"
		)
		(pin "15"
		)
		(pin "16"
		)
		(pin "17"
		)
		(pin "18"
		)
		(pin "19"
		)
		(pin "2"
		)
		(pin "20"
		)
		(pin "21"
		)
		(pin "22"
		)
		(pin "23"
		)
		(pin "24"
		)
		(pin "25"
		)
		(pin "3"
		)
		(pin "4"
		)
		(pin "5"
		)
		(pin "6"
		)
		(pin "7"
		)
		(pin "8"
		)
		(pin "9"
		)
		(instances
			(project "jetson-agx-thor-baseboard"
				(path ""
					(reference "U43")
					(unit 1)
				)
			)
		)
	)
	(symbol
		(lib_id "antmicropower:GND")
		(at 102.87 241.3 0)
		(unit 1)
		(exclude_from_sim no)
		(in_bom yes)
		(on_board yes)
		(dnp no)
		(property "Reference" "#PWR0299"
			(at 102.87 247.65 0)
			(effects
				(font
					(size 1.27 1.27)
				)
				(justify left bottom)
				(hide yes)
			)
		)
		(property "Value" "GND"
			(at 102.87 245.11 0)
			(effects
				(font
					(size 1.27 1.27)
					(thickness 0.15)
				)
			)
		)
		(property "Footprint" ""
			(at 111.76 248.92 0)
			(effects
				(font
					(size 1.27 1.27)
					(thickness 0.15)
				)
				(justify left bottom)
				(hide yes)
			)
		)
		(property "Datasheet" ""
			(at 111.76 254 0)
			(effects
				(font
					(size 1.27 1.27)
					(thickness 0.15)
				)
				(justify left bottom)
				(hide yes)
			)
		)
		(property "Description" ""
			(at 102.87 241.3 0)
			(effects
				(font
					(size 1.27 1.27)
				)
				(hide yes)
			)
		)
		(property "Author" "Antmicro"
			(at 111.76 248.92 0)
			(effects
				(font
					(size 1.27 1.27)
					(thickness 0.15)
				)
				(justify left bottom)
				(hide yes)
			)
		)
		(property "License" "Apache-2.0"
			(at 111.76 251.46 0)
			(effects
				(font
					(size 1.27 1.27)
					(thickness 0.15)
				)
				(justify left bottom)
				(hide yes)
			)
		)
		(pin "1"
		)
		(instances
			(project "jetson-agx-thor-baseboard"
				(path ""
					(reference "#PWR0299")
					(unit 1)
				)
			)
		)
	)
	(symbol
		(lib_id "antmicroCapacitors0402:C_1u_0402")
		(at 349.25 161.29 90)
		(unit 1)
		(exclude_from_sim no)
		(in_bom yes)
		(on_board yes)
		(dnp no)
		(fields_autoplaced yes)
		(property "Reference" "C161"
			(at 351.79 157.4736 90)
			(effects
				(font
					(size 1.27 1.27)
				)
				(justify right)
			)
		)
		(property "Value" "C_1u_0402"
			(at 359.41 140.97 0)
			(effects
				(font
					(size 1.27 1.27)
					(thickness 0.15)
				)
				(justify left bottom)
				(hide yes)
			)
		)
		(property "Footprint" "antmicro-footprints:C_0402_1005Metric"
			(at 361.95 140.97 0)
			(effects
				(font
					(size 1.27 1.27)
					(thickness 0.15)
				)
				(justify left bottom)
				(hide yes)
			)
		)
		(property "Datasheet" "https://product.tdk.com/en/search/capacitor/ceramic/mlcc/info?part_no=C1005X6S1A105K050BC"
			(at 364.49 140.97 0)
			(effects
				(font
					(size 1.27 1.27)
					(thickness 0.15)
				)
				(justify left bottom)
				(hide yes)
			)
		)
		(property "Description" "SMD Multilayer Ceramic Capacitor, 1 µF, 10 V, 0402 [1005 Metric], ± 10%, X6S, C"
			(at 349.25 161.29 0)
			(effects
				(font
					(size 1.27 1.27)
				)
				(hide yes)
			)
		)
		(property "Manufacturer" "TDK"
			(at 369.57 140.97 0)
			(effects
				(font
					(size 1.27 1.27)
					(thickness 0.15)
				)
				(justify left bottom)
				(hide yes)
			)
		)
		(property "MPN" "C1005X6S1A105K050BC"
			(at 367.03 140.97 0)
			(effects
				(font
					(size 1.27 1.27)
					(thickness 0.15)
				)
				(justify left bottom)
				(hide yes)
			)
		)
		(property "Val" "1u"
			(at 351.79 160.0136 90)
			(effects
				(font
					(size 1.27 1.27)
					(thickness 0.15)
				)
				(justify right)
			)
		)
		(property "License" "Apache-2.0"
			(at 372.11 140.97 0)
			(effects
				(font
					(size 1.27 1.27)
					(thickness 0.15)
				)
				(justify left bottom)
				(hide yes)
			)
		)
		(property "Author" "Antmicro"
			(at 374.65 140.97 0)
			(effects
				(font
					(size 1.27 1.27)
					(thickness 0.15)
				)
				(justify left bottom)
				(hide yes)
			)
		)
		(property "Voltage" ""
			(at 377.19 140.97 0)
			(effects
				(font
					(size 1.27 1.27)
				)
				(justify left bottom)
				(hide yes)
			)
		)
		(property "Dielectric" ""
			(at 379.73 140.97 0)
			(effects
				(font
					(size 1.27 1.27)
				)
				(justify left bottom)
				(hide yes)
			)
		)
		(pin "1"
		)
		(pin "2"
		)
		(instances
			(project "jetson-agx-thor-baseboard"
				(path ""
					(reference "C161")
					(unit 1)
				)
			)
		)
	)
	(symbol
		(lib_id "antmicroResistors0402:R_4k7_0402")
		(at 149.86 219.71 90)
		(unit 1)
		(exclude_from_sim no)
		(in_bom yes)
		(on_board yes)
		(dnp no)
		(property "Reference" "R172"
			(at 151.13 215.9 90)
			(effects
				(font
					(size 1.27 1.27)
				)
				(justify right)
			)
		)
		(property "Value" "R_4k7_0402"
			(at 162.56 199.39 0)
			(effects
				(font
					(size 1.27 1.27)
					(thickness 0.15)
				)
				(justify left bottom)
				(hide yes)
			)
		)
		(property "Footprint" "antmicro-footprints:R_0402_1005Metric"
			(at 165.1 199.39 0)
			(effects
				(font
					(size 1.27 1.27)
					(thickness 0.15)
				)
				(justify left bottom)
				(hide yes)
			)
		)
		(property "Datasheet" "https://www.bourns.com/docs/product-datasheets/cr.pdf"
			(at 167.64 199.39 0)
			(effects
				(font
					(size 1.27 1.27)
					(thickness 0.15)
				)
				(justify left bottom)
				(hide yes)
			)
		)
		(property "Description" "SMD Chip Resistor, 4.7 kohm, ± 1%, 62.5 mW, 0402 [1005 Metric], Thick Film, General Purpose"
			(at 149.86 219.71 0)
			(effects
				(font
					(size 1.27 1.27)
				)
				(hide yes)
			)
		)
		(property "Manufacturer" "Bourns"
			(at 172.72 199.39 0)
			(effects
				(font
					(size 1.27 1.27)
					(thickness 0.15)
				)
				(justify left bottom)
				(hide yes)
			)
		)
		(property "MPN" "CR0402-FX-4701GLF"
			(at 170.18 199.39 0)
			(effects
				(font
					(size 1.27 1.27)
					(thickness 0.15)
				)
				(justify left bottom)
				(hide yes)
			)
		)
		(property "Val" "4k7"
			(at 151.13 218.44 90)
			(effects
				(font
					(size 1.27 1.27)
					(thickness 0.15)
				)
				(justify right)
			)
		)
		(property "License" "Apache-2.0"
			(at 175.26 199.39 0)
			(effects
				(font
					(size 1.27 1.27)
					(thickness 0.15)
				)
				(justify left bottom)
				(hide yes)
			)
		)
		(property "Author" "Antmicro"
			(at 177.8 199.39 0)
			(effects
				(font
					(size 1.27 1.27)
					(thickness 0.15)
				)
				(justify left bottom)
				(hide yes)
			)
		)
		(property "Tolerance" "1%"
			(at 160.02 199.39 0)
			(effects
				(font
					(size 1.27 1.27)
				)
				(justify left bottom)
				(hide yes)
			)
		)
		(pin "1"
		)
		(pin "2"
		)
		(instances
			(project "jetson-agx-thor-baseboard"
				(path ""
					(reference "R172")
					(unit 1)
				)
			)
		)
	)
	(symbol
		(lib_id "antmicroResistors0402:R_0R_0402")
		(at 85.09 140.97 90)
		(unit 1)
		(exclude_from_sim no)
		(in_bom no)
		(on_board yes)
		(dnp yes)
		(property "Reference" "R161"
			(at 86.36 137.16 90)
			(effects
				(font
					(size 1.27 1.27)
				)
				(justify right)
			)
		)
		(property "Value" "R_0R_0402"
			(at 97.79 120.65 0)
			(effects
				(font
					(size 1.27 1.27)
					(thickness 0.15)
				)
				(justify left bottom)
				(hide yes)
			)
		)
		(property "Footprint" "antmicro-footprints:R_0402_1005Metric"
			(at 100.33 120.65 0)
			(effects
				(font
					(size 1.27 1.27)
					(thickness 0.15)
				)
				(justify left bottom)
				(hide yes)
			)
		)
		(property "Datasheet" "https://industrial.panasonic.com/cdbs/www-data/pdf/RDA0000/AOA0000C301.pdf"
			(at 102.87 120.65 0)
			(effects
				(font
					(size 1.27 1.27)
					(thickness 0.15)
				)
				(justify left bottom)
				(hide yes)
			)
		)
		(property "Description" "SMD Chip Resistor, Jumper, 0 ohm, 100 mW, 0402 [1005 Metric], Thick Film, General Purpose"
			(at 85.09 140.97 0)
			(effects
				(font
					(size 1.27 1.27)
				)
				(hide yes)
			)
		)
		(property "Manufacturer" "Panasonic"
			(at 107.95 120.65 0)
			(effects
				(font
					(size 1.27 1.27)
					(thickness 0.15)
				)
				(justify left bottom)
				(hide yes)
			)
		)
		(property "MPN" "ERJ2GE0R00X"
			(at 105.41 120.65 0)
			(effects
				(font
					(size 1.27 1.27)
					(thickness 0.15)
				)
				(justify left bottom)
				(hide yes)
			)
		)
		(property "Val" "0R"
			(at 86.36 139.7 90)
			(effects
				(font
					(size 1.27 1.27)
					(thickness 0.15)
				)
				(justify right)
			)
		)
		(property "License" "Apache-2.0"
			(at 110.49 120.65 0)
			(effects
				(font
					(size 1.27 1.27)
					(thickness 0.15)
				)
				(justify left bottom)
				(hide yes)
			)
		)
		(property "Author" "Antmicro"
			(at 113.03 120.65 0)
			(effects
				(font
					(size 1.27 1.27)
					(thickness 0.15)
				)
				(justify left bottom)
				(hide yes)
			)
		)
		(property "Tolerance" "~"
			(at 95.25 120.65 0)
			(effects
				(font
					(size 1.27 1.27)
				)
				(justify left bottom)
				(hide yes)
			)
		)
		(property "Current" "1A"
			(at 115.57 120.65 0)
			(effects
				(font
					(size 1.27 1.27)
					(thickness 0.15)
				)
				(justify left bottom)
				(hide yes)
			)
		)
		(pin "1"
		)
		(pin "2"
		)
		(instances
			(project "jetson-agx-thor-baseboard"
				(path ""
					(reference "R161")
					(unit 1)
				)
			)
		)
	)
	(symbol
		(lib_id "antmicroTestPoints:TP_0.75mm_SMD")
		(at 147.32 99.06 0)
		(unit 1)
		(exclude_from_sim no)
		(in_bom no)
		(on_board yes)
		(dnp no)
		(property "Reference" "TP25"
			(at 151.13 99.0599 0)
			(effects
				(font
					(size 1.27 1.27)
				)
				(justify left)
			)
		)
		(property "Value" "TP_0.75mm_SMD"
			(at 157.48 102.87 0)
			(effects
				(font
					(size 1.27 1.27)
					(thickness 0.15)
				)
				(justify left bottom)
				(hide yes)
			)
		)
		(property "Footprint" "antmicro-footprints:TP_SMD_0.75mm"
			(at 157.48 105.41 0)
			(effects
				(font
					(size 1.27 1.27)
					(thickness 0.15)
				)
				(justify left bottom)
				(hide yes)
			)
		)
		(property "Datasheet" ""
			(at 165.1 111.76 0)
			(effects
				(font
					(size 1.27 1.27)
					(thickness 0.15)
				)
				(justify left bottom)
				(hide yes)
			)
		)
		(property "Description" "SMT test point"
			(at 147.32 99.06 0)
			(effects
				(font
					(size 1.27 1.27)
				)
				(hide yes)
			)
		)
		(property "MPN" ""
			(at 158.115 110.49 0)
			(effects
				(font
					(size 1.27 1.27)
					(thickness 0.15)
				)
				(justify left bottom)
				(hide yes)
			)
		)
		(property "Manufacturer" ""
			(at 158.115 105.41 0)
			(effects
				(font
					(size 1.27 1.27)
					(thickness 0.15)
				)
				(justify left bottom)
				(hide yes)
			)
		)
		(property "Author" "Antmicro"
			(at 157.48 107.95 0)
			(effects
				(font
					(size 1.27 1.27)
					(thickness 0.15)
				)
				(justify left bottom)
				(hide yes)
			)
		)
		(property "License" "Apache-2.0"
			(at 157.48 110.49 0)
			(effects
				(font
					(size 1.27 1.27)
					(thickness 0.15)
				)
				(justify left bottom)
				(hide yes)
			)
		)
		(pin "1"
		)
		(instances
			(project "jetson-agx-thor-baseboard"
				(path ""
					(reference "TP25")
					(unit 1)
				)
			)
		)
	)
	(symbol
		(lib_id "antmicroFCCConnectors:Conn_FFC_WE_68715014522")
		(at 287.02 33.02 0)
		(unit 1)
		(exclude_from_sim no)
		(in_bom yes)
		(on_board yes)
		(dnp no)
		(fields_autoplaced yes)
		(property "Reference" "J11"
			(at 295.91 97.155 0)
			(effects
				(font
					(size 1.27 1.27)
				)
				(justify left)
			)
		)
		(property "Value" "Conn_FFC_WE_68715014522"
			(at 306.07 40.64 0)
			(effects
				(font
					(size 1.27 1.27)
					(thickness 0.15)
				)
				(justify left bottom)
				(hide yes)
			)
		)
		(property "Footprint" "antmicro-footprints:Conn_FFC_WE_68715014x22"
			(at 306.07 43.18 0)
			(effects
				(font
					(size 1.27 1.27)
					(thickness 0.15)
				)
				(justify left bottom)
				(hide yes)
			)
		)
		(property "Datasheet" "https://www.we-online.com/components/products/datasheet/68715014522.pdf"
			(at 306.07 45.72 0)
			(effects
				(font
					(size 1.27 1.27)
					(thickness 0.15)
				)
				(justify left bottom)
				(hide yes)
			)
		)
		(property "Description" "FFC connector"
			(at 287.02 33.02 0)
			(effects
				(font
					(size 1.27 1.27)
				)
				(hide yes)
			)
		)
		(property "MPN" "68715014522"
			(at 295.91 99.695 0)
			(effects
				(font
					(size 1.27 1.27)
					(thickness 0.15)
				)
				(justify left)
			)
		)
		(property "Manufacturer" "Würth Elektronik"
			(at 306.07 50.8 0)
			(effects
				(font
					(size 1.27 1.27)
					(thickness 0.15)
				)
				(justify left bottom)
				(hide yes)
			)
		)
		(property "Author" "Antmicro"
			(at 306.07 53.34 0)
			(effects
				(font
					(size 1.27 1.27)
					(thickness 0.15)
				)
				(justify left bottom)
				(hide yes)
			)
		)
		(property "License" "Apache-2.0"
			(at 306.07 55.88 0)
			(effects
				(font
					(size 1.27 1.27)
					(thickness 0.15)
				)
				(justify left bottom)
				(hide yes)
			)
		)
		(pin "1"
		)
		(pin "10"
		)
		(pin "11"
		)
		(pin "12"
		)
		(pin "13"
		)
		(pin "14"
		)
		(pin "15"
		)
		(pin "16"
		)
		(pin "17"
		)
		(pin "18"
		)
		(pin "19"
		)
		(pin "2"
		)
		(pin "20"
		)
		(pin "21"
		)
		(pin "22"
		)
		(pin "23"
		)
		(pin "24"
		)
		(pin "25"
		)
		(pin "26"
		)
		(pin "27"
		)
		(pin "28"
		)
		(pin "29"
		)
		(pin "3"
		)
		(pin "30"
		)
		(pin "31"
		)
		(pin "32"
		)
		(pin "33"
		)
		(pin "34"
		)
		(pin "35"
		)
		(pin "36"
		)
		(pin "37"
		)
		(pin "38"
		)
		(pin "39"
		)
		(pin "4"
		)
		(pin "40"
		)
		(pin "41"
		)
		(pin "42"
		)
		(pin "43"
		)
		(pin "44"
		)
		(pin "45"
		)
		(pin "46"
		)
		(pin "47"
		)
		(pin "48"
		)
		(pin "49"
		)
		(pin "5"
		)
		(pin "50"
		)
		(pin "6"
		)
		(pin "7"
		)
		(pin "8"
		)
		(pin "9"
		)
		(pin "MP2"
		)
		(pin "MP1"
		)
		(instances
			(project "jetson-agx-thor-baseboard"
				(path ""
					(reference "J11")
					(unit 1)
				)
			)
		)
	)
	(symbol
		(lib_id "antmicroLEDIndicationDiscrete:LED_G_0603_LTST-C190GKT")
		(at 328.93 167.64 90)
		(unit 1)
		(exclude_from_sim no)
		(in_bom yes)
		(on_board yes)
		(dnp no)
		(fields_autoplaced yes)
		(property "Reference" "D27"
			(at 331.47 163.83 90)
			(effects
				(font
					(size 1.27 1.27)
				)
				(justify right)
			)
		)
		(property "Value" "LED_G_0603_LTST-C190GKT"
			(at 336.55 144.78 0)
			(effects
				(font
					(size 1.27 1.27)
					(thickness 0.15)
				)
				(justify left bottom)
				(hide yes)
			)
		)
		(property "Footprint" "antmicro-footprints:LED_0603_1608Metric_G"
			(at 339.09 144.78 0)
			(effects
				(font
					(size 1.27 1.27)
					(thickness 0.15)
				)
				(justify left bottom)
				(hide yes)
			)
		)
		(property "Datasheet" "https://media.digikey.com/pdf/Data%20Sheets/Lite-On%20PDFs/LTST-C190GKT.pdf"
			(at 341.63 144.78 0)
			(effects
				(font
					(size 1.27 1.27)
					(thickness 0.15)
				)
				(justify left bottom)
				(hide yes)
			)
		)
		(property "Description" "LED, Green, SMD, 0603, 20 mA, 2.1 V, 569 nm"
			(at 328.93 167.64 0)
			(effects
				(font
					(size 1.27 1.27)
				)
				(hide yes)
			)
		)
		(property "MPN" "LTST-C190GKT"
			(at 344.17 144.78 0)
			(effects
				(font
					(size 1.27 1.27)
					(thickness 0.15)
				)
				(justify left bottom)
				(hide yes)
			)
		)
		(property "Manufacturer" "Lite-On"
			(at 346.71 144.78 0)
			(effects
				(font
					(size 1.27 1.27)
					(thickness 0.15)
				)
				(justify left bottom)
				(hide yes)
			)
		)
		(property "Author" "Antmicro"
			(at 349.25 144.78 0)
			(effects
				(font
					(size 1.27 1.27)
					(thickness 0.15)
				)
				(justify left bottom)
				(hide yes)
			)
		)
		(property "License" "Apache-2.0"
			(at 351.79 144.78 0)
			(effects
				(font
					(size 1.27 1.27)
					(thickness 0.15)
				)
				(justify left bottom)
				(hide yes)
			)
		)
		(property "Color" "Green"
			(at 331.47 166.37 90)
			(effects
				(font
					(size 1.27 1.27)
				)
				(justify right)
			)
		)
		(pin "1"
		)
		(pin "2"
		)
		(instances
			(project "jetson-agx-thor-baseboard"
				(path ""
					(reference "D27")
					(unit 1)
				)
			)
		)
	)
	(symbol
		(lib_id "antmicroTestPoints:TP_0.75mm_SMD")
		(at 147.32 83.82 0)
		(unit 1)
		(exclude_from_sim no)
		(in_bom no)
		(on_board yes)
		(dnp no)
		(property "Reference" "TP21"
			(at 151.13 83.8199 0)
			(effects
				(font
					(size 1.27 1.27)
				)
				(justify left)
			)
		)
		(property "Value" "TP_0.75mm_SMD"
			(at 157.48 87.63 0)
			(effects
				(font
					(size 1.27 1.27)
					(thickness 0.15)
				)
				(justify left bottom)
				(hide yes)
			)
		)
		(property "Footprint" "antmicro-footprints:TP_SMD_0.75mm"
			(at 157.48 90.17 0)
			(effects
				(font
					(size 1.27 1.27)
					(thickness 0.15)
				)
				(justify left bottom)
				(hide yes)
			)
		)
		(property "Datasheet" ""
			(at 165.1 96.52 0)
			(effects
				(font
					(size 1.27 1.27)
					(thickness 0.15)
				)
				(justify left bottom)
				(hide yes)
			)
		)
		(property "Description" "SMT test point"
			(at 147.32 83.82 0)
			(effects
				(font
					(size 1.27 1.27)
				)
				(hide yes)
			)
		)
		(property "MPN" ""
			(at 158.115 95.25 0)
			(effects
				(font
					(size 1.27 1.27)
					(thickness 0.15)
				)
				(justify left bottom)
				(hide yes)
			)
		)
		(property "Manufacturer" ""
			(at 158.115 90.17 0)
			(effects
				(font
					(size 1.27 1.27)
					(thickness 0.15)
				)
				(justify left bottom)
				(hide yes)
			)
		)
		(property "Author" "Antmicro"
			(at 157.48 92.71 0)
			(effects
				(font
					(size 1.27 1.27)
					(thickness 0.15)
				)
				(justify left bottom)
				(hide yes)
			)
		)
		(property "License" "Apache-2.0"
			(at 157.48 95.25 0)
			(effects
				(font
					(size 1.27 1.27)
					(thickness 0.15)
				)
				(justify left bottom)
				(hide yes)
			)
		)
		(pin "1"
		)
		(instances
			(project "jetson-agx-thor-baseboard"
				(path ""
					(reference "TP21")
					(unit 1)
				)
			)
		)
	)
	(symbol
		(lib_id "antmicroResistors0402:R_0R_0402")
		(at 114.3 140.97 90)
		(unit 1)
		(exclude_from_sim no)
		(in_bom yes)
		(on_board yes)
		(dnp no)
		(property "Reference" "R169"
			(at 113.03 137.16 90)
			(effects
				(font
					(size 1.27 1.27)
				)
				(justify left)
			)
		)
		(property "Value" "R_0R_0402"
			(at 127 120.65 0)
			(effects
				(font
					(size 1.27 1.27)
					(thickness 0.15)
				)
				(justify left bottom)
				(hide yes)
			)
		)
		(property "Footprint" "antmicro-footprints:R_0402_1005Metric"
			(at 129.54 120.65 0)
			(effects
				(font
					(size 1.27 1.27)
					(thickness 0.15)
				)
				(justify left bottom)
				(hide yes)
			)
		)
		(property "Datasheet" "https://industrial.panasonic.com/cdbs/www-data/pdf/RDA0000/AOA0000C301.pdf"
			(at 132.08 120.65 0)
			(effects
				(font
					(size 1.27 1.27)
					(thickness 0.15)
				)
				(justify left bottom)
				(hide yes)
			)
		)
		(property "Description" "SMD Chip Resistor, Jumper, 0 ohm, 100 mW, 0402 [1005 Metric], Thick Film, General Purpose"
			(at 114.3 140.97 0)
			(effects
				(font
					(size 1.27 1.27)
				)
				(hide yes)
			)
		)
		(property "Manufacturer" "Panasonic"
			(at 137.16 120.65 0)
			(effects
				(font
					(size 1.27 1.27)
					(thickness 0.15)
				)
				(justify left bottom)
				(hide yes)
			)
		)
		(property "MPN" "ERJ2GE0R00X"
			(at 134.62 120.65 0)
			(effects
				(font
					(size 1.27 1.27)
					(thickness 0.15)
				)
				(justify left bottom)
				(hide yes)
			)
		)
		(property "Val" "0R"
			(at 113.03 139.7 90)
			(effects
				(font
					(size 1.27 1.27)
					(thickness 0.15)
				)
				(justify left)
			)
		)
		(property "License" "Apache-2.0"
			(at 139.7 120.65 0)
			(effects
				(font
					(size 1.27 1.27)
					(thickness 0.15)
				)
				(justify left bottom)
				(hide yes)
			)
		)
		(property "Author" "Antmicro"
			(at 142.24 120.65 0)
			(effects
				(font
					(size 1.27 1.27)
					(thickness 0.15)
				)
				(justify left bottom)
				(hide yes)
			)
		)
		(property "Tolerance" "~"
			(at 124.46 120.65 0)
			(effects
				(font
					(size 1.27 1.27)
				)
				(justify left bottom)
				(hide yes)
			)
		)
		(property "Current" "1A"
			(at 144.78 120.65 0)
			(effects
				(font
					(size 1.27 1.27)
					(thickness 0.15)
				)
				(justify left bottom)
				(hide yes)
			)
		)
		(pin "1"
		)
		(pin "2"
		)
		(instances
			(project "jetson-agx-thor-baseboard"
				(path ""
					(reference "R169")
					(unit 1)
				)
			)
		)
	)
	(symbol
		(lib_id "antmicroResistors0402:R_0R_0402")
		(at 90.17 68.58 0)
		(mirror y)
		(unit 1)
		(exclude_from_sim no)
		(in_bom yes)
		(on_board yes)
		(dnp no)
		(property "Reference" "R163"
			(at 90.17 67.945 0)
			(effects
				(font
					(size 1.27 1.27)
				)
				(justify right bottom)
			)
		)
		(property "Value" "R_0R_0402"
			(at 69.85 81.28 0)
			(effects
				(font
					(size 1.27 1.27)
					(thickness 0.15)
				)
				(justify left bottom)
				(hide yes)
			)
		)
		(property "Footprint" "antmicro-footprints:R_0402_1005Metric"
			(at 69.85 83.82 0)
			(effects
				(font
					(size 1.27 1.27)
					(thickness 0.15)
				)
				(justify left bottom)
				(hide yes)
			)
		)
		(property "Datasheet" "https://industrial.panasonic.com/cdbs/www-data/pdf/RDA0000/AOA0000C301.pdf"
			(at 69.85 86.36 0)
			(effects
				(font
					(size 1.27 1.27)
					(thickness 0.15)
				)
				(justify left bottom)
				(hide yes)
			)
		)
		(property "Description" "SMD Chip Resistor, Jumper, 0 ohm, 100 mW, 0402 [1005 Metric], Thick Film, General Purpose"
			(at 90.17 68.58 0)
			(effects
				(font
					(size 1.27 1.27)
				)
				(hide yes)
			)
		)
		(property "Manufacturer" "Panasonic"
			(at 69.85 91.44 0)
			(effects
				(font
					(size 1.27 1.27)
					(thickness 0.15)
				)
				(justify left bottom)
				(hide yes)
			)
		)
		(property "MPN" "ERJ2GE0R00X"
			(at 69.85 88.9 0)
			(effects
				(font
					(size 1.27 1.27)
					(thickness 0.15)
				)
				(justify left bottom)
				(hide yes)
			)
		)
		(property "Val" "0R"
			(at 82.55 67.945 0)
			(effects
				(font
					(size 1.27 1.27)
					(thickness 0.15)
				)
				(justify right bottom)
			)
		)
		(property "License" "Apache-2.0"
			(at 69.85 93.98 0)
			(effects
				(font
					(size 1.27 1.27)
					(thickness 0.15)
				)
				(justify left bottom)
				(hide yes)
			)
		)
		(property "Author" "Antmicro"
			(at 69.85 96.52 0)
			(effects
				(font
					(size 1.27 1.27)
					(thickness 0.15)
				)
				(justify left bottom)
				(hide yes)
			)
		)
		(property "Tolerance" "~"
			(at 69.85 78.74 0)
			(effects
				(font
					(size 1.27 1.27)
				)
				(justify left bottom)
				(hide yes)
			)
		)
		(property "Current" "1A"
			(at 69.85 99.06 0)
			(effects
				(font
					(size 1.27 1.27)
					(thickness 0.15)
				)
				(justify left bottom)
				(hide yes)
			)
		)
		(pin "1"
		)
		(pin "2"
		)
		(instances
			(project "jetson-agx-thor-baseboard"
				(path ""
					(reference "R163")
					(unit 1)
				)
			)
		)
	)
	(symbol
		(lib_id "antmicropower:+1V8")
		(at 121.92 134.62 0)
		(unit 1)
		(exclude_from_sim no)
		(in_bom yes)
		(on_board yes)
		(dnp no)
		(property "Reference" "#PWR0303"
			(at 121.92 138.43 0)
			(effects
				(font
					(size 1.27 1.27)
				)
				(justify left bottom)
				(hide yes)
			)
		)
		(property "Value" "+1V8"
			(at 121.285 130.81 0)
			(effects
				(font
					(size 1.27 1.27)
					(thickness 0.15)
				)
			)
		)
		(property "Footprint" ""
			(at 137.16 142.24 0)
			(effects
				(font
					(size 1.27 1.27)
					(thickness 0.15)
				)
				(justify left bottom)
				(hide yes)
			)
		)
		(property "Datasheet" ""
			(at 137.16 144.78 0)
			(effects
				(font
					(size 1.27 1.27)
					(thickness 0.15)
				)
				(justify left bottom)
				(hide yes)
			)
		)
		(property "Description" ""
			(at 121.92 134.62 0)
			(effects
				(font
					(size 1.27 1.27)
				)
				(hide yes)
			)
		)
		(property "Author" "Antmicro"
			(at 137.16 139.7 0)
			(effects
				(font
					(size 1.27 1.27)
					(thickness 0.15)
				)
				(justify left bottom)
				(hide yes)
			)
		)
		(property "License" "Apache-2.0"
			(at 137.16 142.24 0)
			(effects
				(font
					(size 1.27 1.27)
					(thickness 0.15)
				)
				(justify left bottom)
				(hide yes)
			)
		)
		(pin "1"
		)
		(instances
			(project "jetson-agx-thor-baseboard"
				(path ""
					(reference "#PWR0303")
					(unit 1)
				)
			)
		)
	)
	(symbol
		(lib_id "antmicroTestPoints:TP_0.75mm_SMD")
		(at 147.32 109.22 0)
		(unit 1)
		(exclude_from_sim no)
		(in_bom no)
		(on_board yes)
		(dnp no)
		(property "Reference" "TP28"
			(at 151.13 109.2199 0)
			(effects
				(font
					(size 1.27 1.27)
				)
				(justify left)
			)
		)
		(property "Value" "TP_0.75mm_SMD"
			(at 157.48 113.03 0)
			(effects
				(font
					(size 1.27 1.27)
					(thickness 0.15)
				)
				(justify left bottom)
				(hide yes)
			)
		)
		(property "Footprint" "antmicro-footprints:TP_SMD_0.75mm"
			(at 157.48 115.57 0)
			(effects
				(font
					(size 1.27 1.27)
					(thickness 0.15)
				)
				(justify left bottom)
				(hide yes)
			)
		)
		(property "Datasheet" ""
			(at 165.1 121.92 0)
			(effects
				(font
					(size 1.27 1.27)
					(thickness 0.15)
				)
				(justify left bottom)
				(hide yes)
			)
		)
		(property "Description" "SMT test point"
			(at 147.32 109.22 0)
			(effects
				(font
					(size 1.27 1.27)
				)
				(hide yes)
			)
		)
		(property "MPN" ""
			(at 158.115 120.65 0)
			(effects
				(font
					(size 1.27 1.27)
					(thickness 0.15)
				)
				(justify left bottom)
				(hide yes)
			)
		)
		(property "Manufacturer" ""
			(at 158.115 115.57 0)
			(effects
				(font
					(size 1.27 1.27)
					(thickness 0.15)
				)
				(justify left bottom)
				(hide yes)
			)
		)
		(property "Author" "Antmicro"
			(at 157.48 118.11 0)
			(effects
				(font
					(size 1.27 1.27)
					(thickness 0.15)
				)
				(justify left bottom)
				(hide yes)
			)
		)
		(property "License" "Apache-2.0"
			(at 157.48 120.65 0)
			(effects
				(font
					(size 1.27 1.27)
					(thickness 0.15)
				)
				(justify left bottom)
				(hide yes)
			)
		)
		(pin "1"
		)
		(instances
			(project "jetson-agx-thor-baseboard"
				(path ""
					(reference "TP28")
					(unit 1)
				)
			)
		)
	)
	(symbol
		(lib_id "antmicroResistors0402:R_10k_0402")
		(at 113.03 203.2 270)
		(unit 1)
		(exclude_from_sim no)
		(in_bom yes)
		(on_board yes)
		(dnp no)
		(property "Reference" "R168"
			(at 114.3 204.47 90)
			(effects
				(font
					(size 1.27 1.27)
				)
				(justify left)
			)
		)
		(property "Value" "R_10k_0402"
			(at 100.33 223.52 0)
			(effects
				(font
					(size 1.27 1.27)
					(thickness 0.15)
				)
				(justify left bottom)
				(hide yes)
			)
		)
		(property "Footprint" "antmicro-footprints:R_0402_1005Metric"
			(at 97.79 223.52 0)
			(effects
				(font
					(size 1.27 1.27)
					(thickness 0.15)
				)
				(justify left bottom)
				(hide yes)
			)
		)
		(property "Datasheet" "https://www.bourns.com/docs/product-datasheets/cr.pdf"
			(at 95.25 223.52 0)
			(effects
				(font
					(size 1.27 1.27)
					(thickness 0.15)
				)
				(justify left bottom)
				(hide yes)
			)
		)
		(property "Description" "SMD Chip Resistor, 10 kohm, ± 1%, 62.5 mW, 0402 [1005 Metric], Thick Film, General Purpose"
			(at 113.03 203.2 0)
			(effects
				(font
					(size 1.27 1.27)
				)
				(hide yes)
			)
		)
		(property "Manufacturer" "Bourns"
			(at 90.17 223.52 0)
			(effects
				(font
					(size 1.27 1.27)
					(thickness 0.15)
				)
				(justify left bottom)
				(hide yes)
			)
		)
		(property "MPN" "CR0402-FX-1002GLF"
			(at 92.71 223.52 0)
			(effects
				(font
					(size 1.27 1.27)
					(thickness 0.15)
				)
				(justify left bottom)
				(hide yes)
			)
		)
		(property "Val" "10k"
			(at 114.3 207.01 90)
			(effects
				(font
					(size 1.27 1.27)
					(thickness 0.15)
				)
				(justify left)
			)
		)
		(property "License" "Apache-2.0"
			(at 87.63 223.52 0)
			(effects
				(font
					(size 1.27 1.27)
					(thickness 0.15)
				)
				(justify left bottom)
				(hide yes)
			)
		)
		(property "Author" "Antmicro"
			(at 85.09 223.52 0)
			(effects
				(font
					(size 1.27 1.27)
					(thickness 0.15)
				)
				(justify left bottom)
				(hide yes)
			)
		)
		(property "Tolerance" "1%"
			(at 102.87 223.52 0)
			(effects
				(font
					(size 1.27 1.27)
				)
				(justify left bottom)
				(hide yes)
			)
		)
		(pin "1"
		)
		(pin "2"
		)
		(instances
			(project "jetson-agx-thor-baseboard"
				(path ""
					(reference "R168")
					(unit 1)
				)
			)
		)
	)
	(symbol
		(lib_id "antmicroPMICPowerDistributionSwitchesLoadDrivers:AP22615A_TSOT26")
		(at 228.6 210.82 0)
		(unit 1)
		(exclude_from_sim no)
		(in_bom yes)
		(on_board yes)
		(dnp no)
		(property "Reference" "U46"
			(at 236.22 204.47 0)
			(effects
				(font
					(size 1.27 1.27)
				)
			)
		)
		(property "Value" "AP22615A_TSOT26"
			(at 259.08 215.9 0)
			(effects
				(font
					(size 1.27 1.27)
					(thickness 0.15)
				)
				(justify left bottom)
				(hide yes)
			)
		)
		(property "Footprint" "antmicro-footprints:TSOT23-6"
			(at 259.08 218.44 0)
			(effects
				(font
					(size 1.27 1.27)
					(thickness 0.15)
				)
				(justify left bottom)
				(hide yes)
			)
		)
		(property "Datasheet" "https://www.mouser.com/datasheet/2/115/DIOD_S_A0008958405_1-2543193.pdf"
			(at 259.08 220.98 0)
			(effects
				(font
					(size 1.27 1.27)
					(thickness 0.15)
				)
				(justify left bottom)
				(hide yes)
			)
		)
		(property "Description" "Power Load Distribution Switch, High Side, Active High, 1 Output, 5.5 V, 3.6 A, 0.04 ohm, TSOT-26-6"
			(at 228.6 210.82 0)
			(effects
				(font
					(size 1.27 1.27)
				)
				(hide yes)
			)
		)
		(property "MPN" "AP22615AWU-7"
			(at 236.22 207.01 0)
			(effects
				(font
					(size 1.27 1.27)
					(thickness 0.15)
				)
			)
		)
		(property "Manufacturer" "Diodes Incorporated"
			(at 259.08 226.06 0)
			(effects
				(font
					(size 1.27 1.27)
					(thickness 0.15)
				)
				(justify left bottom)
				(hide yes)
			)
		)
		(property "Author" "Antmicro"
			(at 259.08 228.6 0)
			(effects
				(font
					(size 1.27 1.27)
					(thickness 0.15)
				)
				(justify left bottom)
				(hide yes)
			)
		)
		(property "License" "Apache-2.0"
			(at 259.08 231.14 0)
			(effects
				(font
					(size 1.27 1.27)
					(thickness 0.15)
				)
				(justify left bottom)
				(hide yes)
			)
		)
		(pin "1"
		)
		(pin "2"
		)
		(pin "3"
		)
		(pin "4"
		)
		(pin "5"
		)
		(pin "6"
		)
		(instances
			(project "jetson-agx-thor-baseboard"
				(path ""
					(reference "U46")
					(unit 1)
				)
			)
		)
	)
	(symbol
		(lib_id "antmicropower:GND")
		(at 349.25 162.56 0)
		(unit 1)
		(exclude_from_sim no)
		(in_bom yes)
		(on_board yes)
		(dnp no)
		(property "Reference" "#PWR0322"
			(at 349.25 168.91 0)
			(effects
				(font
					(size 1.27 1.27)
				)
				(justify left bottom)
				(hide yes)
			)
		)
		(property "Value" "GND"
			(at 349.25 166.37 0)
			(effects
				(font
					(size 1.27 1.27)
					(thickness 0.15)
				)
			)
		)
		(property "Footprint" ""
			(at 358.14 170.18 0)
			(effects
				(font
					(size 1.27 1.27)
					(thickness 0.15)
				)
				(justify left bottom)
				(hide yes)
			)
		)
		(property "Datasheet" ""
			(at 358.14 175.26 0)
			(effects
				(font
					(size 1.27 1.27)
					(thickness 0.15)
				)
				(justify left bottom)
				(hide yes)
			)
		)
		(property "Description" ""
			(at 349.25 162.56 0)
			(effects
				(font
					(size 1.27 1.27)
				)
				(hide yes)
			)
		)
		(property "Author" "Antmicro"
			(at 358.14 170.18 0)
			(effects
				(font
					(size 1.27 1.27)
					(thickness 0.15)
				)
				(justify left bottom)
				(hide yes)
			)
		)
		(property "License" "Apache-2.0"
			(at 358.14 172.72 0)
			(effects
				(font
					(size 1.27 1.27)
					(thickness 0.15)
				)
				(justify left bottom)
				(hide yes)
			)
		)
		(pin "1"
		)
		(instances
			(project "jetson-agx-thor-baseboard"
				(path ""
					(reference "#PWR0322")
					(unit 1)
				)
			)
		)
	)
	(symbol
		(lib_id "antmicroResistors0402:R_10k_0402")
		(at 92.71 208.28 90)
		(unit 1)
		(exclude_from_sim no)
		(in_bom no)
		(on_board yes)
		(dnp yes)
		(property "Reference" "R165"
			(at 93.98 204.47 90)
			(effects
				(font
					(size 1.27 1.27)
				)
				(justify right)
			)
		)
		(property "Value" "R_10k_0402"
			(at 105.41 187.96 0)
			(effects
				(font
					(size 1.27 1.27)
					(thickness 0.15)
				)
				(justify left bottom)
				(hide yes)
			)
		)
		(property "Footprint" "antmicro-footprints:R_0402_1005Metric"
			(at 107.95 187.96 0)
			(effects
				(font
					(size 1.27 1.27)
					(thickness 0.15)
				)
				(justify left bottom)
				(hide yes)
			)
		)
		(property "Datasheet" "https://www.bourns.com/docs/product-datasheets/cr.pdf"
			(at 110.49 187.96 0)
			(effects
				(font
					(size 1.27 1.27)
					(thickness 0.15)
				)
				(justify left bottom)
				(hide yes)
			)
		)
		(property "Description" "SMD Chip Resistor, 10 kohm, ± 1%, 62.5 mW, 0402 [1005 Metric], Thick Film, General Purpose"
			(at 92.71 208.28 0)
			(effects
				(font
					(size 1.27 1.27)
				)
				(hide yes)
			)
		)
		(property "Manufacturer" "Bourns"
			(at 115.57 187.96 0)
			(effects
				(font
					(size 1.27 1.27)
					(thickness 0.15)
				)
				(justify left bottom)
				(hide yes)
			)
		)
		(property "MPN" "CR0402-FX-1002GLF"
			(at 113.03 187.96 0)
			(effects
				(font
					(size 1.27 1.27)
					(thickness 0.15)
				)
				(justify left bottom)
				(hide yes)
			)
		)
		(property "Val" "10k"
			(at 93.98 207.01 90)
			(effects
				(font
					(size 1.27 1.27)
					(thickness 0.15)
				)
				(justify right)
			)
		)
		(property "License" "Apache-2.0"
			(at 118.11 187.96 0)
			(effects
				(font
					(size 1.27 1.27)
					(thickness 0.15)
				)
				(justify left bottom)
				(hide yes)
			)
		)
		(property "Author" "Antmicro"
			(at 120.65 187.96 0)
			(effects
				(font
					(size 1.27 1.27)
					(thickness 0.15)
				)
				(justify left bottom)
				(hide yes)
			)
		)
		(property "Tolerance" "1%"
			(at 102.87 187.96 0)
			(effects
				(font
					(size 1.27 1.27)
				)
				(justify left bottom)
				(hide yes)
			)
		)
		(pin "1"
		)
		(pin "2"
		)
		(instances
			(project "jetson-agx-thor-baseboard"
				(path ""
					(reference "R165")
					(unit 1)
				)
			)
		)
	)
	(symbol
		(lib_id "antmicropower:+1V8")
		(at 85.09 80.01 0)
		(unit 1)
		(exclude_from_sim no)
		(in_bom yes)
		(on_board yes)
		(dnp no)
		(property "Reference" "#PWR0288"
			(at 85.09 83.82 0)
			(effects
				(font
					(size 1.27 1.27)
				)
				(justify left bottom)
				(hide yes)
			)
		)
		(property "Value" "+1V8"
			(at 81.915 76.2 0)
			(effects
				(font
					(size 1.27 1.27)
					(thickness 0.15)
				)
				(justify left)
			)
		)
		(property "Footprint" ""
			(at 100.33 87.63 0)
			(effects
				(font
					(size 1.27 1.27)
					(thickness 0.15)
				)
				(justify left bottom)
				(hide yes)
			)
		)
		(property "Datasheet" ""
			(at 100.33 90.17 0)
			(effects
				(font
					(size 1.27 1.27)
					(thickness 0.15)
				)
				(justify left bottom)
				(hide yes)
			)
		)
		(property "Description" ""
			(at 85.09 80.01 0)
			(effects
				(font
					(size 1.27 1.27)
				)
				(hide yes)
			)
		)
		(property "Author" "Antmicro"
			(at 100.33 85.09 0)
			(effects
				(font
					(size 1.27 1.27)
					(thickness 0.15)
				)
				(justify left bottom)
				(hide yes)
			)
		)
		(property "License" "Apache-2.0"
			(at 100.33 87.63 0)
			(effects
				(font
					(size 1.27 1.27)
					(thickness 0.15)
				)
				(justify left bottom)
				(hide yes)
			)
		)
		(pin "1"
		)
		(instances
			(project "jetson-agx-thor-baseboard"
				(path ""
					(reference "#PWR0288")
					(unit 1)
				)
			)
		)
	)
	(symbol
		(lib_id "antmicropower:GND")
		(at 364.49 218.44 0)
		(unit 1)
		(exclude_from_sim no)
		(in_bom yes)
		(on_board yes)
		(dnp no)
		(property "Reference" "#PWR0333"
			(at 364.49 224.79 0)
			(effects
				(font
					(size 1.27 1.27)
				)
				(justify left bottom)
				(hide yes)
			)
		)
		(property "Value" "GND"
			(at 364.49 222.25 0)
			(effects
				(font
					(size 1.27 1.27)
					(thickness 0.15)
				)
			)
		)
		(property "Footprint" ""
			(at 373.38 226.06 0)
			(effects
				(font
					(size 1.27 1.27)
					(thickness 0.15)
				)
				(justify left bottom)
				(hide yes)
			)
		)
		(property "Datasheet" ""
			(at 373.38 231.14 0)
			(effects
				(font
					(size 1.27 1.27)
					(thickness 0.15)
				)
				(justify left bottom)
				(hide yes)
			)
		)
		(property "Description" ""
			(at 364.49 218.44 0)
			(effects
				(font
					(size 1.27 1.27)
				)
				(hide yes)
			)
		)
		(property "Author" "Antmicro"
			(at 373.38 226.06 0)
			(effects
				(font
					(size 1.27 1.27)
					(thickness 0.15)
				)
				(justify left bottom)
				(hide yes)
			)
		)
		(property "License" "Apache-2.0"
			(at 373.38 228.6 0)
			(effects
				(font
					(size 1.27 1.27)
					(thickness 0.15)
				)
				(justify left bottom)
				(hide yes)
			)
		)
		(pin "1"
		)
		(instances
			(project "jetson-agx-thor-baseboard"
				(path ""
					(reference "#PWR0333")
					(unit 1)
				)
			)
		)
	)
	(symbol
		(lib_id "antmicroResistors0402:R_2k2_0402")
		(at 96.52 151.13 270)
		(unit 1)
		(exclude_from_sim no)
		(in_bom yes)
		(on_board yes)
		(dnp no)
		(property "Reference" "R390"
			(at 95.504 146.558 0)
			(effects
				(font
					(size 1.27 1.27)
					(thickness 0.15)
				)
				(justify left)
			)
		)
		(property "Value" "R_2k2_0402"
			(at 83.82 171.45 0)
			(effects
				(font
					(size 1.27 1.27)
					(thickness 0.15)
				)
				(justify left bottom)
				(hide yes)
			)
		)
		(property "Footprint" "antmicro-footprints:R_0402_1005Metric"
			(at 81.28 171.45 0)
			(effects
				(font
					(size 1.27 1.27)
					(thickness 0.15)
				)
				(justify left bottom)
				(hide yes)
			)
		)
		(property "Datasheet" "https://www.bourns.com/docs/product-datasheets/cr.pdf"
			(at 78.74 171.45 0)
			(effects
				(font
					(size 1.27 1.27)
					(thickness 0.15)
				)
				(justify left bottom)
				(hide yes)
			)
		)
		(property "Description" "SMD Chip Resistor, 2.2 kohm, ± 1%, 62.5 mW, 0402 [1005 Metric], Thick Film, General Purpose"
			(at 66.04 171.45 0)
			(effects
				(font
					(size 1.27 1.27)
				)
				(justify left bottom)
				(hide yes)
			)
		)
		(property "MPN" "CR0402-FX-2201GLF"
			(at 76.2 171.45 0)
			(effects
				(font
					(size 1.27 1.27)
					(thickness 0.15)
				)
				(justify left bottom)
				(hide yes)
			)
		)
		(property "Manufacturer" "Bourns"
			(at 73.66 171.45 0)
			(effects
				(font
					(size 1.27 1.27)
					(thickness 0.15)
				)
				(justify left bottom)
				(hide yes)
			)
		)
		(property "License" "Apache-2.0"
			(at 71.12 171.45 0)
			(effects
				(font
					(size 1.27 1.27)
					(thickness 0.15)
				)
				(justify left bottom)
				(hide yes)
			)
		)
		(property "Author" "Antmicro"
			(at 68.58 171.45 0)
			(effects
				(font
					(size 1.27 1.27)
					(thickness 0.15)
				)
				(justify left bottom)
				(hide yes)
			)
		)
		(property "Val" "2k2"
			(at 95.504 155.702 0)
			(effects
				(font
					(size 1.27 1.27)
					(thickness 0.15)
				)
				(justify left)
			)
		)
		(property "Tolerance" "1%"
			(at 86.36 171.45 0)
			(effects
				(font
					(size 1.27 1.27)
				)
				(justify left bottom)
				(hide yes)
			)
		)
		(pin "1"
		)
		(pin "2"
		)
		(instances
			(project "jetson-agx-thor-baseboard"
				(path ""
					(reference "R390")
					(unit 1)
				)
			)
		)
	)
	(symbol
		(lib_id "antmicropower:GND")
		(at 344.17 162.56 0)
		(unit 1)
		(exclude_from_sim no)
		(in_bom yes)
		(on_board yes)
		(dnp no)
		(property "Reference" "#PWR0321"
			(at 344.17 168.91 0)
			(effects
				(font
					(size 1.27 1.27)
				)
				(justify left bottom)
				(hide yes)
			)
		)
		(property "Value" "GND"
			(at 344.17 166.37 0)
			(effects
				(font
					(size 1.27 1.27)
					(thickness 0.15)
				)
			)
		)
		(property "Footprint" ""
			(at 353.06 170.18 0)
			(effects
				(font
					(size 1.27 1.27)
					(thickness 0.15)
				)
				(justify left bottom)
				(hide yes)
			)
		)
		(property "Datasheet" ""
			(at 353.06 175.26 0)
			(effects
				(font
					(size 1.27 1.27)
					(thickness 0.15)
				)
				(justify left bottom)
				(hide yes)
			)
		)
		(property "Description" ""
			(at 344.17 162.56 0)
			(effects
				(font
					(size 1.27 1.27)
				)
				(hide yes)
			)
		)
		(property "Author" "Antmicro"
			(at 353.06 170.18 0)
			(effects
				(font
					(size 1.27 1.27)
					(thickness 0.15)
				)
				(justify left bottom)
				(hide yes)
			)
		)
		(property "License" "Apache-2.0"
			(at 353.06 172.72 0)
			(effects
				(font
					(size 1.27 1.27)
					(thickness 0.15)
				)
				(justify left bottom)
				(hide yes)
			)
		)
		(pin "1"
		)
		(instances
			(project "jetson-agx-thor-baseboard"
				(path ""
					(reference "#PWR0321")
					(unit 1)
				)
			)
		)
	)
	(symbol
		(lib_id "antmicroCapacitors0402:C_1u_0402")
		(at 266.7 161.29 90)
		(unit 1)
		(exclude_from_sim no)
		(in_bom yes)
		(on_board yes)
		(dnp no)
		(fields_autoplaced yes)
		(property "Reference" "C164"
			(at 264.16 157.4736 90)
			(effects
				(font
					(size 1.27 1.27)
				)
				(justify left)
			)
		)
		(property "Value" "C_1u_0402"
			(at 276.86 140.97 0)
			(effects
				(font
					(size 1.27 1.27)
					(thickness 0.15)
				)
				(justify left bottom)
				(hide yes)
			)
		)
		(property "Footprint" "antmicro-footprints:C_0402_1005Metric"
			(at 279.4 140.97 0)
			(effects
				(font
					(size 1.27 1.27)
					(thickness 0.15)
				)
				(justify left bottom)
				(hide yes)
			)
		)
		(property "Datasheet" "https://product.tdk.com/en/search/capacitor/ceramic/mlcc/info?part_no=C1005X6S1A105K050BC"
			(at 281.94 140.97 0)
			(effects
				(font
					(size 1.27 1.27)
					(thickness 0.15)
				)
				(justify left bottom)
				(hide yes)
			)
		)
		(property "Description" "SMD Multilayer Ceramic Capacitor, 1 µF, 10 V, 0402 [1005 Metric], ± 10%, X6S, C"
			(at 266.7 161.29 0)
			(effects
				(font
					(size 1.27 1.27)
				)
				(hide yes)
			)
		)
		(property "Manufacturer" "TDK"
			(at 287.02 140.97 0)
			(effects
				(font
					(size 1.27 1.27)
					(thickness 0.15)
				)
				(justify left bottom)
				(hide yes)
			)
		)
		(property "MPN" "C1005X6S1A105K050BC"
			(at 284.48 140.97 0)
			(effects
				(font
					(size 1.27 1.27)
					(thickness 0.15)
				)
				(justify left bottom)
				(hide yes)
			)
		)
		(property "Val" "1u"
			(at 264.16 160.0136 90)
			(effects
				(font
					(size 1.27 1.27)
					(thickness 0.15)
				)
				(justify left)
			)
		)
		(property "License" "Apache-2.0"
			(at 289.56 140.97 0)
			(effects
				(font
					(size 1.27 1.27)
					(thickness 0.15)
				)
				(justify left bottom)
				(hide yes)
			)
		)
		(property "Author" "Antmicro"
			(at 292.1 140.97 0)
			(effects
				(font
					(size 1.27 1.27)
					(thickness 0.15)
				)
				(justify left bottom)
				(hide yes)
			)
		)
		(property "Voltage" ""
			(at 294.64 140.97 0)
			(effects
				(font
					(size 1.27 1.27)
				)
				(justify left bottom)
				(hide yes)
			)
		)
		(property "Dielectric" ""
			(at 297.18 140.97 0)
			(effects
				(font
					(size 1.27 1.27)
				)
				(justify left bottom)
				(hide yes)
			)
		)
		(pin "1"
		)
		(pin "2"
		)
		(instances
			(project "jetson-agx-thor-baseboard"
				(path ""
					(reference "C164")
					(unit 1)
				)
			)
		)
	)
	(symbol
		(lib_id "antmicroResistors0402:R_10k_0402")
		(at 222.25 203.2 270)
		(unit 1)
		(exclude_from_sim no)
		(in_bom yes)
		(on_board yes)
		(dnp no)
		(property "Reference" "R176"
			(at 223.52 204.47 90)
			(effects
				(font
					(size 1.27 1.27)
				)
				(justify left)
			)
		)
		(property "Value" "R_10k_0402"
			(at 209.55 223.52 0)
			(effects
				(font
					(size 1.27 1.27)
					(thickness 0.15)
				)
				(justify left bottom)
				(hide yes)
			)
		)
		(property "Footprint" "antmicro-footprints:R_0402_1005Metric"
			(at 207.01 223.52 0)
			(effects
				(font
					(size 1.27 1.27)
					(thickness 0.15)
				)
				(justify left bottom)
				(hide yes)
			)
		)
		(property "Datasheet" "https://www.bourns.com/docs/product-datasheets/cr.pdf"
			(at 204.47 223.52 0)
			(effects
				(font
					(size 1.27 1.27)
					(thickness 0.15)
				)
				(justify left bottom)
				(hide yes)
			)
		)
		(property "Description" "SMD Chip Resistor, 10 kohm, ± 1%, 62.5 mW, 0402 [1005 Metric], Thick Film, General Purpose"
			(at 222.25 203.2 0)
			(effects
				(font
					(size 1.27 1.27)
				)
				(hide yes)
			)
		)
		(property "Manufacturer" "Bourns"
			(at 199.39 223.52 0)
			(effects
				(font
					(size 1.27 1.27)
					(thickness 0.15)
				)
				(justify left bottom)
				(hide yes)
			)
		)
		(property "MPN" "CR0402-FX-1002GLF"
			(at 201.93 223.52 0)
			(effects
				(font
					(size 1.27 1.27)
					(thickness 0.15)
				)
				(justify left bottom)
				(hide yes)
			)
		)
		(property "Val" "10k"
			(at 223.52 207.01 90)
			(effects
				(font
					(size 1.27 1.27)
					(thickness 0.15)
				)
				(justify left)
			)
		)
		(property "License" "Apache-2.0"
			(at 196.85 223.52 0)
			(effects
				(font
					(size 1.27 1.27)
					(thickness 0.15)
				)
				(justify left bottom)
				(hide yes)
			)
		)
		(property "Author" "Antmicro"
			(at 194.31 223.52 0)
			(effects
				(font
					(size 1.27 1.27)
					(thickness 0.15)
				)
				(justify left bottom)
				(hide yes)
			)
		)
		(property "Tolerance" "1%"
			(at 212.09 223.52 0)
			(effects
				(font
					(size 1.27 1.27)
				)
				(justify left bottom)
				(hide yes)
			)
		)
		(pin "1"
		)
		(pin "2"
		)
		(instances
			(project "jetson-agx-thor-baseboard"
				(path ""
					(reference "R176")
					(unit 1)
				)
			)
		)
	)
	(symbol
		(lib_id "antmicropower:GND")
		(at 361.95 163.83 0)
		(unit 1)
		(exclude_from_sim no)
		(in_bom yes)
		(on_board yes)
		(dnp no)
		(property "Reference" "#PWR0323"
			(at 361.95 170.18 0)
			(effects
				(font
					(size 1.27 1.27)
				)
				(justify left bottom)
				(hide yes)
			)
		)
		(property "Value" "GND"
			(at 361.95 167.64 0)
			(effects
				(font
					(size 1.27 1.27)
					(thickness 0.15)
				)
			)
		)
		(property "Footprint" ""
			(at 370.84 171.45 0)
			(effects
				(font
					(size 1.27 1.27)
					(thickness 0.15)
				)
				(justify left bottom)
				(hide yes)
			)
		)
		(property "Datasheet" ""
			(at 370.84 176.53 0)
			(effects
				(font
					(size 1.27 1.27)
					(thickness 0.15)
				)
				(justify left bottom)
				(hide yes)
			)
		)
		(property "Description" ""
			(at 361.95 163.83 0)
			(effects
				(font
					(size 1.27 1.27)
				)
				(hide yes)
			)
		)
		(property "Author" "Antmicro"
			(at 370.84 171.45 0)
			(effects
				(font
					(size 1.27 1.27)
					(thickness 0.15)
				)
				(justify left bottom)
				(hide yes)
			)
		)
		(property "License" "Apache-2.0"
			(at 370.84 173.99 0)
			(effects
				(font
					(size 1.27 1.27)
					(thickness 0.15)
				)
				(justify left bottom)
				(hide yes)
			)
		)
		(pin "1"
		)
		(instances
			(project "jetson-agx-thor-baseboard"
				(path ""
					(reference "#PWR0323")
					(unit 1)
				)
			)
		)
	)
	(symbol
		(lib_id "antmicropower:GND")
		(at 372.11 204.47 0)
		(unit 1)
		(exclude_from_sim no)
		(in_bom yes)
		(on_board yes)
		(dnp no)
		(property "Reference" "#PWR0336"
			(at 372.11 210.82 0)
			(effects
				(font
					(size 1.27 1.27)
				)
				(justify left bottom)
				(hide yes)
			)
		)
		(property "Value" "GND"
			(at 372.11 208.28 0)
			(effects
				(font
					(size 1.27 1.27)
					(thickness 0.15)
				)
			)
		)
		(property "Footprint" ""
			(at 381 212.09 0)
			(effects
				(font
					(size 1.27 1.27)
					(thickness 0.15)
				)
				(justify left bottom)
				(hide yes)
			)
		)
		(property "Datasheet" ""
			(at 381 217.17 0)
			(effects
				(font
					(size 1.27 1.27)
					(thickness 0.15)
				)
				(justify left bottom)
				(hide yes)
			)
		)
		(property "Description" ""
			(at 372.11 204.47 0)
			(effects
				(font
					(size 1.27 1.27)
				)
				(hide yes)
			)
		)
		(property "Author" "Antmicro"
			(at 381 212.09 0)
			(effects
				(font
					(size 1.27 1.27)
					(thickness 0.15)
				)
				(justify left bottom)
				(hide yes)
			)
		)
		(property "License" "Apache-2.0"
			(at 381 214.63 0)
			(effects
				(font
					(size 1.27 1.27)
					(thickness 0.15)
				)
				(justify left bottom)
				(hide yes)
			)
		)
		(pin "1"
		)
		(instances
			(project "jetson-agx-thor-baseboard"
				(path ""
					(reference "#PWR0336")
					(unit 1)
				)
			)
		)
	)
	(symbol
		(lib_id "antmicroResistors0402:R_100k_0402")
		(at 97.79 255.27 90)
		(unit 1)
		(exclude_from_sim no)
		(in_bom yes)
		(on_board yes)
		(dnp no)
		(property "Reference" "R166"
			(at 99.06 251.46 90)
			(effects
				(font
					(size 1.27 1.27)
				)
				(justify right)
			)
		)
		(property "Value" "R_100k_0402"
			(at 110.49 234.95 0)
			(effects
				(font
					(size 1.27 1.27)
					(thickness 0.15)
				)
				(justify left bottom)
				(hide yes)
			)
		)
		(property "Footprint" "antmicro-footprints:R_0402_1005Metric"
			(at 113.03 234.95 0)
			(effects
				(font
					(size 1.27 1.27)
					(thickness 0.15)
				)
				(justify left bottom)
				(hide yes)
			)
		)
		(property "Datasheet" "https://www.bourns.com/docs/product-datasheets/cr.pdf"
			(at 115.57 234.95 0)
			(effects
				(font
					(size 1.27 1.27)
					(thickness 0.15)
				)
				(justify left bottom)
				(hide yes)
			)
		)
		(property "Description" "SMD Chip Resistor, 100 kohm, ± 1%, 62.5 mW, 0402 [1005 Metric], Thick Film, General Purpose"
			(at 97.79 255.27 0)
			(effects
				(font
					(size 1.27 1.27)
				)
				(hide yes)
			)
		)
		(property "Manufacturer" "Bourns"
			(at 120.65 234.95 0)
			(effects
				(font
					(size 1.27 1.27)
					(thickness 0.15)
				)
				(justify left bottom)
				(hide yes)
			)
		)
		(property "MPN" "CR0402-FX-1003GLF"
			(at 118.11 234.95 0)
			(effects
				(font
					(size 1.27 1.27)
					(thickness 0.15)
				)
				(justify left bottom)
				(hide yes)
			)
		)
		(property "Val" "100k"
			(at 99.06 254 90)
			(effects
				(font
					(size 1.27 1.27)
					(thickness 0.15)
				)
				(justify right)
			)
		)
		(property "License" "Apache-2.0"
			(at 123.19 234.95 0)
			(effects
				(font
					(size 1.27 1.27)
					(thickness 0.15)
				)
				(justify left bottom)
				(hide yes)
			)
		)
		(property "Author" "Antmicro"
			(at 125.73 234.95 0)
			(effects
				(font
					(size 1.27 1.27)
					(thickness 0.15)
				)
				(justify left bottom)
				(hide yes)
			)
		)
		(property "Tolerance" "1%"
			(at 107.95 234.95 0)
			(effects
				(font
					(size 1.27 1.27)
				)
				(justify left bottom)
				(hide yes)
			)
		)
		(pin "1"
		)
		(pin "2"
		)
		(instances
			(project "jetson-agx-thor-baseboard"
				(path ""
					(reference "R166")
					(unit 1)
				)
			)
		)
	)
	(symbol
		(lib_id "antmicropower:GND")
		(at 246.38 168.91 0)
		(unit 1)
		(exclude_from_sim no)
		(in_bom yes)
		(on_board yes)
		(dnp no)
		(property "Reference" "#PWR0324"
			(at 246.38 175.26 0)
			(effects
				(font
					(size 1.27 1.27)
				)
				(justify left bottom)
				(hide yes)
			)
		)
		(property "Value" "GND"
			(at 246.38 172.72 0)
			(effects
				(font
					(size 1.27 1.27)
					(thickness 0.15)
				)
			)
		)
		(property "Footprint" ""
			(at 255.27 176.53 0)
			(effects
				(font
					(size 1.27 1.27)
					(thickness 0.15)
				)
				(justify left bottom)
				(hide yes)
			)
		)
		(property "Datasheet" ""
			(at 255.27 181.61 0)
			(effects
				(font
					(size 1.27 1.27)
					(thickness 0.15)
				)
				(justify left bottom)
				(hide yes)
			)
		)
		(property "Description" ""
			(at 246.38 168.91 0)
			(effects
				(font
					(size 1.27 1.27)
				)
				(hide yes)
			)
		)
		(property "Author" "Antmicro"
			(at 255.27 176.53 0)
			(effects
				(font
					(size 1.27 1.27)
					(thickness 0.15)
				)
				(justify left bottom)
				(hide yes)
			)
		)
		(property "License" "Apache-2.0"
			(at 255.27 179.07 0)
			(effects
				(font
					(size 1.27 1.27)
					(thickness 0.15)
				)
				(justify left bottom)
				(hide yes)
			)
		)
		(pin "1"
		)
		(instances
			(project "jetson-agx-thor-baseboard"
				(path ""
					(reference "#PWR0324")
					(unit 1)
				)
			)
		)
	)
	(symbol
		(lib_id "antmicroTestPoints:TP_0.75mm_SMD")
		(at 147.32 86.36 0)
		(unit 1)
		(exclude_from_sim no)
		(in_bom no)
		(on_board yes)
		(dnp no)
		(property "Reference" "TP22"
			(at 153.67 86.36 0)
			(effects
				(font
					(size 1.27 1.27)
				)
			)
		)
		(property "Value" "TP_0.75mm_SMD"
			(at 157.48 90.17 0)
			(effects
				(font
					(size 1.27 1.27)
					(thickness 0.15)
				)
				(justify left bottom)
				(hide yes)
			)
		)
		(property "Footprint" "antmicro-footprints:TP_SMD_0.75mm"
			(at 157.48 92.71 0)
			(effects
				(font
					(size 1.27 1.27)
					(thickness 0.15)
				)
				(justify left bottom)
				(hide yes)
			)
		)
		(property "Datasheet" ""
			(at 165.1 99.06 0)
			(effects
				(font
					(size 1.27 1.27)
					(thickness 0.15)
				)
				(justify left bottom)
				(hide yes)
			)
		)
		(property "Description" "SMT test point"
			(at 147.32 86.36 0)
			(effects
				(font
					(size 1.27 1.27)
				)
				(hide yes)
			)
		)
		(property "MPN" ""
			(at 158.115 97.79 0)
			(effects
				(font
					(size 1.27 1.27)
					(thickness 0.15)
				)
				(justify left bottom)
				(hide yes)
			)
		)
		(property "Manufacturer" ""
			(at 158.115 92.71 0)
			(effects
				(font
					(size 1.27 1.27)
					(thickness 0.15)
				)
				(justify left bottom)
				(hide yes)
			)
		)
		(property "Author" "Antmicro"
			(at 157.48 95.25 0)
			(effects
				(font
					(size 1.27 1.27)
					(thickness 0.15)
				)
				(justify left bottom)
				(hide yes)
			)
		)
		(property "License" "Apache-2.0"
			(at 157.48 97.79 0)
			(effects
				(font
					(size 1.27 1.27)
					(thickness 0.15)
				)
				(justify left bottom)
				(hide yes)
			)
		)
		(pin "1"
		)
		(instances
			(project "jetson-agx-thor-baseboard"
				(path ""
					(reference "TP22")
					(unit 1)
				)
			)
		)
	)
	(symbol
		(lib_id "antmicroResistors0402:R_2k2_0402")
		(at 133.35 151.13 270)
		(unit 1)
		(exclude_from_sim no)
		(in_bom yes)
		(on_board yes)
		(dnp no)
		(property "Reference" "R393"
			(at 132.334 146.558 0)
			(effects
				(font
					(size 1.27 1.27)
					(thickness 0.15)
				)
				(justify left)
			)
		)
		(property "Value" "R_2k2_0402"
			(at 120.65 171.45 0)
			(effects
				(font
					(size 1.27 1.27)
					(thickness 0.15)
				)
				(justify left bottom)
				(hide yes)
			)
		)
		(property "Footprint" "antmicro-footprints:R_0402_1005Metric"
			(at 118.11 171.45 0)
			(effects
				(font
					(size 1.27 1.27)
					(thickness 0.15)
				)
				(justify left bottom)
				(hide yes)
			)
		)
		(property "Datasheet" "https://www.bourns.com/docs/product-datasheets/cr.pdf"
			(at 115.57 171.45 0)
			(effects
				(font
					(size 1.27 1.27)
					(thickness 0.15)
				)
				(justify left bottom)
				(hide yes)
			)
		)
		(property "Description" "SMD Chip Resistor, 2.2 kohm, ± 1%, 62.5 mW, 0402 [1005 Metric], Thick Film, General Purpose"
			(at 102.87 171.45 0)
			(effects
				(font
					(size 1.27 1.27)
				)
				(justify left bottom)
				(hide yes)
			)
		)
		(property "MPN" "CR0402-FX-2201GLF"
			(at 113.03 171.45 0)
			(effects
				(font
					(size 1.27 1.27)
					(thickness 0.15)
				)
				(justify left bottom)
				(hide yes)
			)
		)
		(property "Manufacturer" "Bourns"
			(at 110.49 171.45 0)
			(effects
				(font
					(size 1.27 1.27)
					(thickness 0.15)
				)
				(justify left bottom)
				(hide yes)
			)
		)
		(property "License" "Apache-2.0"
			(at 107.95 171.45 0)
			(effects
				(font
					(size 1.27 1.27)
					(thickness 0.15)
				)
				(justify left bottom)
				(hide yes)
			)
		)
		(property "Author" "Antmicro"
			(at 105.41 171.45 0)
			(effects
				(font
					(size 1.27 1.27)
					(thickness 0.15)
				)
				(justify left bottom)
				(hide yes)
			)
		)
		(property "Val" "2k2"
			(at 132.334 155.702 0)
			(effects
				(font
					(size 1.27 1.27)
					(thickness 0.15)
				)
				(justify left)
			)
		)
		(property "Tolerance" "1%"
			(at 123.19 171.45 0)
			(effects
				(font
					(size 1.27 1.27)
				)
				(justify left bottom)
				(hide yes)
			)
		)
		(pin "1"
		)
		(pin "2"
		)
		(instances
			(project "jetson-agx-thor-baseboard"
				(path ""
					(reference "R393")
					(unit 1)
				)
			)
		)
	)
	(symbol
		(lib_id "antmicropower:GND")
		(at 212.09 209.55 0)
		(unit 1)
		(exclude_from_sim no)
		(in_bom yes)
		(on_board yes)
		(dnp no)
		(property "Reference" "#PWR0311"
			(at 212.09 215.9 0)
			(effects
				(font
					(size 1.27 1.27)
				)
				(justify left bottom)
				(hide yes)
			)
		)
		(property "Value" "GND"
			(at 212.09 213.36 0)
			(effects
				(font
					(size 1.27 1.27)
					(thickness 0.15)
				)
			)
		)
		(property "Footprint" ""
			(at 220.98 217.17 0)
			(effects
				(font
					(size 1.27 1.27)
					(thickness 0.15)
				)
				(justify left bottom)
				(hide yes)
			)
		)
		(property "Datasheet" ""
			(at 220.98 222.25 0)
			(effects
				(font
					(size 1.27 1.27)
					(thickness 0.15)
				)
				(justify left bottom)
				(hide yes)
			)
		)
		(property "Description" ""
			(at 212.09 209.55 0)
			(effects
				(font
					(size 1.27 1.27)
				)
				(hide yes)
			)
		)
		(property "Author" "Antmicro"
			(at 220.98 217.17 0)
			(effects
				(font
					(size 1.27 1.27)
					(thickness 0.15)
				)
				(justify left bottom)
				(hide yes)
			)
		)
		(property "License" "Apache-2.0"
			(at 220.98 219.71 0)
			(effects
				(font
					(size 1.27 1.27)
					(thickness 0.15)
				)
				(justify left bottom)
				(hide yes)
			)
		)
		(pin "1"
		)
		(instances
			(project "jetson-agx-thor-baseboard"
				(path ""
					(reference "#PWR0311")
					(unit 1)
				)
			)
		)
	)
	(symbol
		(lib_id "antmicroPMICPowerDistributionSwitchesLoadDrivers:AP22615A_TSOT26")
		(at 119.38 210.82 0)
		(unit 1)
		(exclude_from_sim no)
		(in_bom yes)
		(on_board yes)
		(dnp no)
		(property "Reference" "U44"
			(at 127 204.47 0)
			(effects
				(font
					(size 1.27 1.27)
				)
			)
		)
		(property "Value" "AP22615A_TSOT26"
			(at 149.86 215.9 0)
			(effects
				(font
					(size 1.27 1.27)
					(thickness 0.15)
				)
				(justify left bottom)
				(hide yes)
			)
		)
		(property "Footprint" "antmicro-footprints:TSOT23-6"
			(at 149.86 218.44 0)
			(effects
				(font
					(size 1.27 1.27)
					(thickness 0.15)
				)
				(justify left bottom)
				(hide yes)
			)
		)
		(property "Datasheet" "https://www.mouser.com/datasheet/2/115/DIOD_S_A0008958405_1-2543193.pdf"
			(at 149.86 220.98 0)
			(effects
				(font
					(size 1.27 1.27)
					(thickness 0.15)
				)
				(justify left bottom)
				(hide yes)
			)
		)
		(property "Description" "Power Load Distribution Switch, High Side, Active High, 1 Output, 5.5 V, 3.6 A, 0.04 ohm, TSOT-26-6"
			(at 119.38 210.82 0)
			(effects
				(font
					(size 1.27 1.27)
				)
				(hide yes)
			)
		)
		(property "MPN" "AP22615AWU-7"
			(at 127 207.01 0)
			(effects
				(font
					(size 1.27 1.27)
					(thickness 0.15)
				)
			)
		)
		(property "Manufacturer" "Diodes Incorporated"
			(at 149.86 226.06 0)
			(effects
				(font
					(size 1.27 1.27)
					(thickness 0.15)
				)
				(justify left bottom)
				(hide yes)
			)
		)
		(property "Author" "Antmicro"
			(at 149.86 228.6 0)
			(effects
				(font
					(size 1.27 1.27)
					(thickness 0.15)
				)
				(justify left bottom)
				(hide yes)
			)
		)
		(property "License" "Apache-2.0"
			(at 149.86 231.14 0)
			(effects
				(font
					(size 1.27 1.27)
					(thickness 0.15)
				)
				(justify left bottom)
				(hide yes)
			)
		)
		(pin "1"
		)
		(pin "2"
		)
		(pin "3"
		)
		(pin "4"
		)
		(pin "5"
		)
		(pin "6"
		)
		(instances
			(project "jetson-agx-thor-baseboard"
				(path ""
					(reference "U44")
					(unit 1)
				)
			)
		)
	)
	(symbol
		(lib_id "antmicropower:GND")
		(at 372.11 233.68 0)
		(unit 1)
		(exclude_from_sim no)
		(in_bom yes)
		(on_board yes)
		(dnp no)
		(property "Reference" "#PWR0338"
			(at 372.11 240.03 0)
			(effects
				(font
					(size 1.27 1.27)
				)
				(justify left bottom)
				(hide yes)
			)
		)
		(property "Value" "GND"
			(at 372.11 237.49 0)
			(effects
				(font
					(size 1.27 1.27)
					(thickness 0.15)
				)
			)
		)
		(property "Footprint" ""
			(at 381 241.3 0)
			(effects
				(font
					(size 1.27 1.27)
					(thickness 0.15)
				)
				(justify left bottom)
				(hide yes)
			)
		)
		(property "Datasheet" ""
			(at 381 246.38 0)
			(effects
				(font
					(size 1.27 1.27)
					(thickness 0.15)
				)
				(justify left bottom)
				(hide yes)
			)
		)
		(property "Description" ""
			(at 372.11 233.68 0)
			(effects
				(font
					(size 1.27 1.27)
				)
				(hide yes)
			)
		)
		(property "Author" "Antmicro"
			(at 381 241.3 0)
			(effects
				(font
					(size 1.27 1.27)
					(thickness 0.15)
				)
				(justify left bottom)
				(hide yes)
			)
		)
		(property "License" "Apache-2.0"
			(at 381 243.84 0)
			(effects
				(font
					(size 1.27 1.27)
					(thickness 0.15)
				)
				(justify left bottom)
				(hide yes)
			)
		)
		(pin "1"
		)
		(instances
			(project "jetson-agx-thor-baseboard"
				(path ""
					(reference "#PWR0338")
					(unit 1)
				)
			)
		)
	)
	(symbol
		(lib_id "antmicroResistors0402:R_0R_0402")
		(at 349.25 134.62 0)
		(unit 1)
		(exclude_from_sim no)
		(in_bom yes)
		(on_board yes)
		(dnp no)
		(property "Reference" "R397"
			(at 356.108 133.604 0)
			(effects
				(font
					(size 1.27 1.27)
					(thickness 0.15)
				)
			)
		)
		(property "Value" "R_0R_0402"
			(at 369.57 147.32 0)
			(effects
				(font
					(size 1.27 1.27)
					(thickness 0.15)
				)
				(justify left bottom)
				(hide yes)
			)
		)
		(property "Footprint" "antmicro-footprints:R_0402_1005Metric"
			(at 369.57 149.86 0)
			(effects
				(font
					(size 1.27 1.27)
					(thickness 0.15)
				)
				(justify left bottom)
				(hide yes)
			)
		)
		(property "Datasheet" "https://industrial.panasonic.com/cdbs/www-data/pdf/RDA0000/AOA0000C301.pdf"
			(at 369.57 152.4 0)
			(effects
				(font
					(size 1.27 1.27)
					(thickness 0.15)
				)
				(justify left bottom)
				(hide yes)
			)
		)
		(property "Description" "SMD Chip Resistor, Jumper, 0 ohm, 100 mW, 0402 [1005 Metric], Thick Film, General Purpose"
			(at 369.57 167.64 0)
			(effects
				(font
					(size 1.27 1.27)
				)
				(justify left bottom)
				(hide yes)
			)
		)
		(property "MPN" "ERJ2GE0R00X"
			(at 369.57 154.94 0)
			(effects
				(font
					(size 1.27 1.27)
					(thickness 0.15)
				)
				(justify left bottom)
				(hide yes)
			)
		)
		(property "Manufacturer" "Panasonic"
			(at 369.57 157.48 0)
			(effects
				(font
					(size 1.27 1.27)
					(thickness 0.15)
				)
				(justify left bottom)
				(hide yes)
			)
		)
		(property "License" "Apache-2.0"
			(at 369.57 160.02 0)
			(effects
				(font
					(size 1.27 1.27)
					(thickness 0.15)
				)
				(justify left bottom)
				(hide yes)
			)
		)
		(property "Author" "Antmicro"
			(at 369.57 162.56 0)
			(effects
				(font
					(size 1.27 1.27)
					(thickness 0.15)
				)
				(justify left bottom)
				(hide yes)
			)
		)
		(property "Val" "0R"
			(at 348.488 133.604 0)
			(effects
				(font
					(size 1.27 1.27)
					(thickness 0.15)
				)
			)
		)
		(property "Tolerance" "~"
			(at 369.57 144.78 0)
			(effects
				(font
					(size 1.27 1.27)
				)
				(justify left bottom)
				(hide yes)
			)
		)
		(property "Current" "1A"
			(at 369.57 165.1 0)
			(effects
				(font
					(size 1.27 1.27)
					(thickness 0.15)
				)
				(justify left bottom)
				(hide yes)
			)
		)
		(pin "2"
		)
		(pin "1"
		)
		(instances
			(project "jetson-agx-thor-baseboard"
				(path ""
					(reference "R397")
					(unit 1)
				)
			)
		)
	)
	(symbol
		(lib_id "antmicroCapacitors0402:C_100n_0402")
		(at 102.87 234.95 90)
		(mirror x)
		(unit 1)
		(exclude_from_sim no)
		(in_bom yes)
		(on_board yes)
		(dnp no)
		(property "Reference" "C157"
			(at 104.775 236.22 90)
			(effects
				(font
					(size 1.27 1.27)
				)
				(justify right)
			)
		)
		(property "Value" "C_100n_0402"
			(at 113.03 255.27 0)
			(effects
				(font
					(size 1.27 1.27)
					(thickness 0.15)
				)
				(justify left bottom)
				(hide yes)
			)
		)
		(property "Footprint" "antmicro-footprints:C_0402_1005Metric"
			(at 115.57 255.27 0)
			(effects
				(font
					(size 1.27 1.27)
					(thickness 0.15)
				)
				(justify left bottom)
				(hide yes)
			)
		)
		(property "Datasheet" "https://www.murata.com/products/productdetail?partno=GRM155R61H104KE14%23"
			(at 118.11 255.27 0)
			(effects
				(font
					(size 1.27 1.27)
					(thickness 0.15)
				)
				(justify left bottom)
				(hide yes)
			)
		)
		(property "Description" "SMD Multilayer Ceramic Capacitor, 0.1 µF, 50 V, 0402 [1005 Metric], ± 10%, X5R, GRM Series"
			(at 102.87 234.95 0)
			(effects
				(font
					(size 1.27 1.27)
				)
				(hide yes)
			)
		)
		(property "Manufacturer" "Murata"
			(at 123.19 255.27 0)
			(effects
				(font
					(size 1.27 1.27)
					(thickness 0.15)
				)
				(justify left bottom)
				(hide yes)
			)
		)
		(property "MPN" "GRM155R61H104KE14D"
			(at 120.65 255.27 0)
			(effects
				(font
					(size 1.27 1.27)
					(thickness 0.15)
				)
				(justify left bottom)
				(hide yes)
			)
		)
		(property "Val" "100n"
			(at 104.775 238.76 90)
			(effects
				(font
					(size 1.27 1.27)
					(thickness 0.15)
				)
				(justify right)
			)
		)
		(property "License" "Apache-2.0"
			(at 125.73 255.27 0)
			(effects
				(font
					(size 1.27 1.27)
					(thickness 0.15)
				)
				(justify left bottom)
				(hide yes)
			)
		)
		(property "Author" "Antmicro"
			(at 128.27 255.27 0)
			(effects
				(font
					(size 1.27 1.27)
					(thickness 0.15)
				)
				(justify left bottom)
				(hide yes)
			)
		)
		(property "Voltage" "50V"
			(at 130.81 255.27 0)
			(effects
				(font
					(size 1.27 1.27)
				)
				(justify left bottom)
				(hide yes)
			)
		)
		(property "Dielectric" "X5R"
			(at 133.35 255.27 0)
			(effects
				(font
					(size 1.27 1.27)
				)
				(justify left bottom)
				(hide yes)
			)
		)
		(pin "1"
		)
		(pin "2"
		)
		(instances
			(project "jetson-agx-thor-baseboard"
				(path ""
					(reference "C157")
					(unit 1)
				)
			)
		)
	)
	(symbol
		(lib_id "antmicroCapacitors0402:C_100n_0402")
		(at 99.06 55.88 90)
		(unit 1)
		(exclude_from_sim no)
		(in_bom yes)
		(on_board yes)
		(dnp no)
		(fields_autoplaced yes)
		(property "Reference" "C155"
			(at 101.6 52.0636 90)
			(effects
				(font
					(size 1.27 1.27)
				)
				(justify right)
			)
		)
		(property "Value" "C_100n_0402"
			(at 109.22 35.56 0)
			(effects
				(font
					(size 1.27 1.27)
					(thickness 0.15)
				)
				(justify left bottom)
				(hide yes)
			)
		)
		(property "Footprint" "antmicro-footprints:C_0402_1005Metric"
			(at 111.76 35.56 0)
			(effects
				(font
					(size 1.27 1.27)
					(thickness 0.15)
				)
				(justify left bottom)
				(hide yes)
			)
		)
		(property "Datasheet" "https://www.murata.com/products/productdetail?partno=GRM155R61H104KE14%23"
			(at 114.3 35.56 0)
			(effects
				(font
					(size 1.27 1.27)
					(thickness 0.15)
				)
				(justify left bottom)
				(hide yes)
			)
		)
		(property "Description" "SMD Multilayer Ceramic Capacitor, 0.1 µF, 50 V, 0402 [1005 Metric], ± 10%, X5R, GRM Series"
			(at 99.06 55.88 0)
			(effects
				(font
					(size 1.27 1.27)
				)
				(hide yes)
			)
		)
		(property "Manufacturer" "Murata"
			(at 119.38 35.56 0)
			(effects
				(font
					(size 1.27 1.27)
					(thickness 0.15)
				)
				(justify left bottom)
				(hide yes)
			)
		)
		(property "MPN" "GRM155R61H104KE14D"
			(at 116.84 35.56 0)
			(effects
				(font
					(size 1.27 1.27)
					(thickness 0.15)
				)
				(justify left bottom)
				(hide yes)
			)
		)
		(property "Val" "100n"
			(at 101.6 54.6036 90)
			(effects
				(font
					(size 1.27 1.27)
					(thickness 0.15)
				)
				(justify right)
			)
		)
		(property "License" "Apache-2.0"
			(at 121.92 35.56 0)
			(effects
				(font
					(size 1.27 1.27)
					(thickness 0.15)
				)
				(justify left bottom)
				(hide yes)
			)
		)
		(property "Author" "Antmicro"
			(at 124.46 35.56 0)
			(effects
				(font
					(size 1.27 1.27)
					(thickness 0.15)
				)
				(justify left bottom)
				(hide yes)
			)
		)
		(property "Voltage" "50V"
			(at 127 35.56 0)
			(effects
				(font
					(size 1.27 1.27)
				)
				(justify left bottom)
				(hide yes)
			)
		)
		(property "Dielectric" "X5R"
			(at 129.54 35.56 0)
			(effects
				(font
					(size 1.27 1.27)
				)
				(justify left bottom)
				(hide yes)
			)
		)
		(pin "1"
		)
		(pin "2"
		)
		(instances
			(project "jetson-agx-thor-baseboard"
				(path ""
					(reference "C155")
					(unit 1)
				)
			)
		)
	)
	(symbol
		(lib_id "antmicropower:GND")
		(at 245.11 220.98 0)
		(unit 1)
		(exclude_from_sim no)
		(in_bom yes)
		(on_board yes)
		(dnp no)
		(property "Reference" "#PWR0315"
			(at 245.11 227.33 0)
			(effects
				(font
					(size 1.27 1.27)
				)
				(justify left bottom)
				(hide yes)
			)
		)
		(property "Value" "GND"
			(at 245.11 224.79 0)
			(effects
				(font
					(size 1.27 1.27)
					(thickness 0.15)
				)
			)
		)
		(property "Footprint" ""
			(at 254 228.6 0)
			(effects
				(font
					(size 1.27 1.27)
					(thickness 0.15)
				)
				(justify left bottom)
				(hide yes)
			)
		)
		(property "Datasheet" ""
			(at 254 233.68 0)
			(effects
				(font
					(size 1.27 1.27)
					(thickness 0.15)
				)
				(justify left bottom)
				(hide yes)
			)
		)
		(property "Description" ""
			(at 245.11 220.98 0)
			(effects
				(font
					(size 1.27 1.27)
				)
				(hide yes)
			)
		)
		(property "Author" "Antmicro"
			(at 254 228.6 0)
			(effects
				(font
					(size 1.27 1.27)
					(thickness 0.15)
				)
				(justify left bottom)
				(hide yes)
			)
		)
		(property "License" "Apache-2.0"
			(at 254 231.14 0)
			(effects
				(font
					(size 1.27 1.27)
					(thickness 0.15)
				)
				(justify left bottom)
				(hide yes)
			)
		)
		(pin "1"
		)
		(instances
			(project "jetson-agx-thor-baseboard"
				(path ""
					(reference "#PWR0315")
					(unit 1)
				)
			)
		)
	)
	(symbol
		(lib_id "antmicropower:+3V3")
		(at 102.87 232.41 0)
		(unit 1)
		(exclude_from_sim no)
		(in_bom yes)
		(on_board yes)
		(dnp no)
		(property "Reference" "#PWR0298"
			(at 102.87 236.22 0)
			(effects
				(font
					(size 1.27 1.27)
				)
				(justify left bottom)
				(hide yes)
			)
		)
		(property "Value" "+3V3"
			(at 99.695 229.235 0)
			(effects
				(font
					(size 1.27 1.27)
					(thickness 0.15)
				)
				(justify left bottom)
			)
		)
		(property "Footprint" ""
			(at 118.11 240.03 0)
			(effects
				(font
					(size 1.27 1.27)
					(thickness 0.15)
				)
				(justify left bottom)
				(hide yes)
			)
		)
		(property "Datasheet" ""
			(at 118.11 242.57 0)
			(effects
				(font
					(size 1.27 1.27)
					(thickness 0.15)
				)
				(justify left bottom)
				(hide yes)
			)
		)
		(property "Description" ""
			(at 102.87 232.41 0)
			(effects
				(font
					(size 1.27 1.27)
				)
				(hide yes)
			)
		)
		(property "Author" "Antmicro"
			(at 118.11 234.95 0)
			(effects
				(font
					(size 1.27 1.27)
					(thickness 0.15)
				)
				(justify left bottom)
				(hide yes)
			)
		)
		(property "License" "Apache-2.0"
			(at 118.11 237.49 0)
			(effects
				(font
					(size 1.27 1.27)
					(thickness 0.15)
				)
				(justify left bottom)
				(hide yes)
			)
		)
		(pin "1"
		)
		(instances
			(project "jetson-agx-thor-baseboard"
				(path ""
					(reference "#PWR0298")
					(unit 1)
				)
			)
		)
	)
	(symbol
		(lib_id "antmicroPMICPowerDistributionSwitchesLoadDrivers:AP22615A_TSOT26")
		(at 119.38 243.84 0)
		(unit 1)
		(exclude_from_sim no)
		(in_bom yes)
		(on_board yes)
		(dnp no)
		(property "Reference" "U45"
			(at 127 237.49 0)
			(effects
				(font
					(size 1.27 1.27)
				)
			)
		)
		(property "Value" "AP22615A_TSOT26"
			(at 149.86 248.92 0)
			(effects
				(font
					(size 1.27 1.27)
					(thickness 0.15)
				)
				(justify left bottom)
				(hide yes)
			)
		)
		(property "Footprint" "antmicro-footprints:TSOT23-6"
			(at 149.86 251.46 0)
			(effects
				(font
					(size 1.27 1.27)
					(thickness 0.15)
				)
				(justify left bottom)
				(hide yes)
			)
		)
		(property "Datasheet" "https://www.mouser.com/datasheet/2/115/DIOD_S_A0008958405_1-2543193.pdf"
			(at 149.86 254 0)
			(effects
				(font
					(size 1.27 1.27)
					(thickness 0.15)
				)
				(justify left bottom)
				(hide yes)
			)
		)
		(property "Description" "Power Load Distribution Switch, High Side, Active High, 1 Output, 5.5 V, 3.6 A, 0.04 ohm, TSOT-26-6"
			(at 119.38 243.84 0)
			(effects
				(font
					(size 1.27 1.27)
				)
				(hide yes)
			)
		)
		(property "MPN" "AP22615AWU-7"
			(at 127 240.03 0)
			(effects
				(font
					(size 1.27 1.27)
					(thickness 0.15)
				)
			)
		)
		(property "Manufacturer" "Diodes Incorporated"
			(at 149.86 259.08 0)
			(effects
				(font
					(size 1.27 1.27)
					(thickness 0.15)
				)
				(justify left bottom)
				(hide yes)
			)
		)
		(property "Author" "Antmicro"
			(at 149.86 261.62 0)
			(effects
				(font
					(size 1.27 1.27)
					(thickness 0.15)
				)
				(justify left bottom)
				(hide yes)
			)
		)
		(property "License" "Apache-2.0"
			(at 149.86 264.16 0)
			(effects
				(font
					(size 1.27 1.27)
					(thickness 0.15)
				)
				(justify left bottom)
				(hide yes)
			)
		)
		(pin "1"
		)
		(pin "2"
		)
		(pin "3"
		)
		(pin "4"
		)
		(pin "5"
		)
		(pin "6"
		)
		(instances
			(project "jetson-agx-thor-baseboard"
				(path ""
					(reference "U45")
					(unit 1)
				)
			)
		)
	)
	(symbol
		(lib_id "antmicroResistors0402:R_2k2_0402")
		(at 99.06 151.13 270)
		(unit 1)
		(exclude_from_sim no)
		(in_bom yes)
		(on_board yes)
		(dnp no)
		(property "Reference" "R391"
			(at 98.044 146.558 0)
			(effects
				(font
					(size 1.27 1.27)
					(thickness 0.15)
				)
				(justify left)
			)
		)
		(property "Value" "R_2k2_0402"
			(at 86.36 171.45 0)
			(effects
				(font
					(size 1.27 1.27)
					(thickness 0.15)
				)
				(justify left bottom)
				(hide yes)
			)
		)
		(property "Footprint" "antmicro-footprints:R_0402_1005Metric"
			(at 83.82 171.45 0)
			(effects
				(font
					(size 1.27 1.27)
					(thickness 0.15)
				)
				(justify left bottom)
				(hide yes)
			)
		)
		(property "Datasheet" "https://www.bourns.com/docs/product-datasheets/cr.pdf"
			(at 81.28 171.45 0)
			(effects
				(font
					(size 1.27 1.27)
					(thickness 0.15)
				)
				(justify left bottom)
				(hide yes)
			)
		)
		(property "Description" "SMD Chip Resistor, 2.2 kohm, ± 1%, 62.5 mW, 0402 [1005 Metric], Thick Film, General Purpose"
			(at 68.58 171.45 0)
			(effects
				(font
					(size 1.27 1.27)
				)
				(justify left bottom)
				(hide yes)
			)
		)
		(property "MPN" "CR0402-FX-2201GLF"
			(at 78.74 171.45 0)
			(effects
				(font
					(size 1.27 1.27)
					(thickness 0.15)
				)
				(justify left bottom)
				(hide yes)
			)
		)
		(property "Manufacturer" "Bourns"
			(at 76.2 171.45 0)
			(effects
				(font
					(size 1.27 1.27)
					(thickness 0.15)
				)
				(justify left bottom)
				(hide yes)
			)
		)
		(property "License" "Apache-2.0"
			(at 73.66 171.45 0)
			(effects
				(font
					(size 1.27 1.27)
					(thickness 0.15)
				)
				(justify left bottom)
				(hide yes)
			)
		)
		(property "Author" "Antmicro"
			(at 71.12 171.45 0)
			(effects
				(font
					(size 1.27 1.27)
					(thickness 0.15)
				)
				(justify left bottom)
				(hide yes)
			)
		)
		(property "Val" "2k2"
			(at 98.044 155.702 0)
			(effects
				(font
					(size 1.27 1.27)
					(thickness 0.15)
				)
				(justify left)
			)
		)
		(property "Tolerance" "1%"
			(at 88.9 171.45 0)
			(effects
				(font
					(size 1.27 1.27)
				)
				(justify left bottom)
				(hide yes)
			)
		)
		(pin "1"
		)
		(pin "2"
		)
		(instances
			(project "jetson-agx-thor-baseboard"
				(path ""
					(reference "R391")
					(unit 1)
				)
			)
		)
	)
	(symbol
		(lib_id "antmicroCapacitors0402:C_100n_0402")
		(at 372.11 232.41 270)
		(mirror x)
		(unit 1)
		(exclude_from_sim no)
		(in_bom yes)
		(on_board yes)
		(dnp no)
		(property "Reference" "C167"
			(at 374.015 228.6 90)
			(effects
				(font
					(size 1.27 1.27)
				)
				(justify left)
			)
		)
		(property "Value" "C_100n_0402"
			(at 361.95 212.09 0)
			(effects
				(font
					(size 1.27 1.27)
					(thickness 0.15)
				)
				(justify left bottom)
				(hide yes)
			)
		)
		(property "Footprint" "antmicro-footprints:C_0402_1005Metric"
			(at 359.41 212.09 0)
			(effects
				(font
					(size 1.27 1.27)
					(thickness 0.15)
				)
				(justify left bottom)
				(hide yes)
			)
		)
		(property "Datasheet" "https://www.murata.com/products/productdetail?partno=GRM155R61H104KE14%23"
			(at 356.87 212.09 0)
			(effects
				(font
					(size 1.27 1.27)
					(thickness 0.15)
				)
				(justify left bottom)
				(hide yes)
			)
		)
		(property "Description" "SMD Multilayer Ceramic Capacitor, 0.1 µF, 50 V, 0402 [1005 Metric], ± 10%, X5R, GRM Series"
			(at 372.11 232.41 0)
			(effects
				(font
					(size 1.27 1.27)
				)
				(hide yes)
			)
		)
		(property "Manufacturer" "Murata"
			(at 351.79 212.09 0)
			(effects
				(font
					(size 1.27 1.27)
					(thickness 0.15)
				)
				(justify left bottom)
				(hide yes)
			)
		)
		(property "MPN" "GRM155R61H104KE14D"
			(at 354.33 212.09 0)
			(effects
				(font
					(size 1.27 1.27)
					(thickness 0.15)
				)
				(justify left bottom)
				(hide yes)
			)
		)
		(property "Val" "100n"
			(at 374.015 231.14 90)
			(effects
				(font
					(size 1.27 1.27)
					(thickness 0.15)
				)
				(justify left)
			)
		)
		(property "License" "Apache-2.0"
			(at 349.25 212.09 0)
			(effects
				(font
					(size 1.27 1.27)
					(thickness 0.15)
				)
				(justify left bottom)
				(hide yes)
			)
		)
		(property "Author" "Antmicro"
			(at 346.71 212.09 0)
			(effects
				(font
					(size 1.27 1.27)
					(thickness 0.15)
				)
				(justify left bottom)
				(hide yes)
			)
		)
		(property "Voltage" "50V"
			(at 344.17 212.09 0)
			(effects
				(font
					(size 1.27 1.27)
				)
				(justify left bottom)
				(hide yes)
			)
		)
		(property "Dielectric" "X5R"
			(at 341.63 212.09 0)
			(effects
				(font
					(size 1.27 1.27)
				)
				(justify left bottom)
				(hide yes)
			)
		)
		(pin "1"
		)
		(pin "2"
		)
		(instances
			(project "jetson-agx-thor-baseboard"
				(path ""
					(reference "C167")
					(unit 1)
				)
			)
		)
	)
	(symbol
		(lib_id "antmicropower:GND")
		(at 149.86 254 0)
		(unit 1)
		(exclude_from_sim no)
		(in_bom yes)
		(on_board yes)
		(dnp no)
		(property "Reference" "#PWR0307"
			(at 149.86 260.35 0)
			(effects
				(font
					(size 1.27 1.27)
				)
				(justify left bottom)
				(hide yes)
			)
		)
		(property "Value" "GND"
			(at 149.86 257.81 0)
			(effects
				(font
					(size 1.27 1.27)
					(thickness 0.15)
				)
			)
		)
		(property "Footprint" ""
			(at 158.75 261.62 0)
			(effects
				(font
					(size 1.27 1.27)
					(thickness 0.15)
				)
				(justify left bottom)
				(hide yes)
			)
		)
		(property "Datasheet" ""
			(at 158.75 266.7 0)
			(effects
				(font
					(size 1.27 1.27)
					(thickness 0.15)
				)
				(justify left bottom)
				(hide yes)
			)
		)
		(property "Description" ""
			(at 149.86 254 0)
			(effects
				(font
					(size 1.27 1.27)
				)
				(hide yes)
			)
		)
		(property "Author" "Antmicro"
			(at 158.75 261.62 0)
			(effects
				(font
					(size 1.27 1.27)
					(thickness 0.15)
				)
				(justify left bottom)
				(hide yes)
			)
		)
		(property "License" "Apache-2.0"
			(at 158.75 264.16 0)
			(effects
				(font
					(size 1.27 1.27)
					(thickness 0.15)
				)
				(justify left bottom)
				(hide yes)
			)
		)
		(pin "1"
		)
		(instances
			(project "jetson-agx-thor-baseboard"
				(path ""
					(reference "#PWR0307")
					(unit 1)
				)
			)
		)
	)
	(symbol
		(lib_id "antmicroResistors0402:R_0R_0402")
		(at 349.25 137.16 0)
		(unit 1)
		(exclude_from_sim no)
		(in_bom yes)
		(on_board yes)
		(dnp no)
		(property "Reference" "R398"
			(at 356.108 136.144 0)
			(effects
				(font
					(size 1.27 1.27)
					(thickness 0.15)
				)
			)
		)
		(property "Value" "R_0R_0402"
			(at 369.57 149.86 0)
			(effects
				(font
					(size 1.27 1.27)
					(thickness 0.15)
				)
				(justify left bottom)
				(hide yes)
			)
		)
		(property "Footprint" "antmicro-footprints:R_0402_1005Metric"
			(at 369.57 152.4 0)
			(effects
				(font
					(size 1.27 1.27)
					(thickness 0.15)
				)
				(justify left bottom)
				(hide yes)
			)
		)
		(property "Datasheet" "https://industrial.panasonic.com/cdbs/www-data/pdf/RDA0000/AOA0000C301.pdf"
			(at 369.57 154.94 0)
			(effects
				(font
					(size 1.27 1.27)
					(thickness 0.15)
				)
				(justify left bottom)
				(hide yes)
			)
		)
		(property "Description" "SMD Chip Resistor, Jumper, 0 ohm, 100 mW, 0402 [1005 Metric], Thick Film, General Purpose"
			(at 369.57 170.18 0)
			(effects
				(font
					(size 1.27 1.27)
				)
				(justify left bottom)
				(hide yes)
			)
		)
		(property "MPN" "ERJ2GE0R00X"
			(at 369.57 157.48 0)
			(effects
				(font
					(size 1.27 1.27)
					(thickness 0.15)
				)
				(justify left bottom)
				(hide yes)
			)
		)
		(property "Manufacturer" "Panasonic"
			(at 369.57 160.02 0)
			(effects
				(font
					(size 1.27 1.27)
					(thickness 0.15)
				)
				(justify left bottom)
				(hide yes)
			)
		)
		(property "License" "Apache-2.0"
			(at 369.57 162.56 0)
			(effects
				(font
					(size 1.27 1.27)
					(thickness 0.15)
				)
				(justify left bottom)
				(hide yes)
			)
		)
		(property "Author" "Antmicro"
			(at 369.57 165.1 0)
			(effects
				(font
					(size 1.27 1.27)
					(thickness 0.15)
				)
				(justify left bottom)
				(hide yes)
			)
		)
		(property "Val" "0R"
			(at 348.488 136.144 0)
			(effects
				(font
					(size 1.27 1.27)
					(thickness 0.15)
				)
			)
		)
		(property "Tolerance" "~"
			(at 369.57 147.32 0)
			(effects
				(font
					(size 1.27 1.27)
				)
				(justify left bottom)
				(hide yes)
			)
		)
		(property "Current" "1A"
			(at 369.57 167.64 0)
			(effects
				(font
					(size 1.27 1.27)
					(thickness 0.15)
				)
				(justify left bottom)
				(hide yes)
			)
		)
		(pin "2"
		)
		(pin "1"
		)
		(instances
			(project "jetson-agx-thor-baseboard"
				(path ""
					(reference "R398")
					(unit 1)
				)
			)
		)
	)
	(symbol
		(lib_id "antmicroResistors0402:R_0R_0402")
		(at 121.92 140.97 90)
		(unit 1)
		(exclude_from_sim no)
		(in_bom no)
		(on_board yes)
		(dnp yes)
		(property "Reference" "R170"
			(at 123.19 137.16 90)
			(effects
				(font
					(size 1.27 1.27)
				)
				(justify right)
			)
		)
		(property "Value" "R_0R_0402"
			(at 134.62 120.65 0)
			(effects
				(font
					(size 1.27 1.27)
					(thickness 0.15)
				)
				(justify left bottom)
				(hide yes)
			)
		)
		(property "Footprint" "antmicro-footprints:R_0402_1005Metric"
			(at 137.16 120.65 0)
			(effects
				(font
					(size 1.27 1.27)
					(thickness 0.15)
				)
				(justify left bottom)
				(hide yes)
			)
		)
		(property "Datasheet" "https://industrial.panasonic.com/cdbs/www-data/pdf/RDA0000/AOA0000C301.pdf"
			(at 139.7 120.65 0)
			(effects
				(font
					(size 1.27 1.27)
					(thickness 0.15)
				)
				(justify left bottom)
				(hide yes)
			)
		)
		(property "Description" "SMD Chip Resistor, Jumper, 0 ohm, 100 mW, 0402 [1005 Metric], Thick Film, General Purpose"
			(at 121.92 140.97 0)
			(effects
				(font
					(size 1.27 1.27)
				)
				(hide yes)
			)
		)
		(property "Manufacturer" "Panasonic"
			(at 144.78 120.65 0)
			(effects
				(font
					(size 1.27 1.27)
					(thickness 0.15)
				)
				(justify left bottom)
				(hide yes)
			)
		)
		(property "MPN" "ERJ2GE0R00X"
			(at 142.24 120.65 0)
			(effects
				(font
					(size 1.27 1.27)
					(thickness 0.15)
				)
				(justify left bottom)
				(hide yes)
			)
		)
		(property "Val" "0R"
			(at 123.19 139.7 90)
			(effects
				(font
					(size 1.27 1.27)
					(thickness 0.15)
				)
				(justify right)
			)
		)
		(property "License" "Apache-2.0"
			(at 147.32 120.65 0)
			(effects
				(font
					(size 1.27 1.27)
					(thickness 0.15)
				)
				(justify left bottom)
				(hide yes)
			)
		)
		(property "Author" "Antmicro"
			(at 149.86 120.65 0)
			(effects
				(font
					(size 1.27 1.27)
					(thickness 0.15)
				)
				(justify left bottom)
				(hide yes)
			)
		)
		(property "Tolerance" "~"
			(at 132.08 120.65 0)
			(effects
				(font
					(size 1.27 1.27)
				)
				(justify left bottom)
				(hide yes)
			)
		)
		(property "Current" "1A"
			(at 152.4 120.65 0)
			(effects
				(font
					(size 1.27 1.27)
					(thickness 0.15)
				)
				(justify left bottom)
				(hide yes)
			)
		)
		(pin "1"
		)
		(pin "2"
		)
		(instances
			(project "jetson-agx-thor-baseboard"
				(path ""
					(reference "R170")
					(unit 1)
				)
			)
		)
	)
	(symbol
		(lib_id "antmicropower:GND")
		(at 364.49 247.65 0)
		(unit 1)
		(exclude_from_sim no)
		(in_bom yes)
		(on_board yes)
		(dnp no)
		(property "Reference" "#PWR0334"
			(at 364.49 254 0)
			(effects
				(font
					(size 1.27 1.27)
				)
				(justify left bottom)
				(hide yes)
			)
		)
		(property "Value" "GND"
			(at 364.49 251.46 0)
			(effects
				(font
					(size 1.27 1.27)
					(thickness 0.15)
				)
			)
		)
		(property "Footprint" ""
			(at 373.38 255.27 0)
			(effects
				(font
					(size 1.27 1.27)
					(thickness 0.15)
				)
				(justify left bottom)
				(hide yes)
			)
		)
		(property "Datasheet" ""
			(at 373.38 260.35 0)
			(effects
				(font
					(size 1.27 1.27)
					(thickness 0.15)
				)
				(justify left bottom)
				(hide yes)
			)
		)
		(property "Description" ""
			(at 364.49 247.65 0)
			(effects
				(font
					(size 1.27 1.27)
				)
				(hide yes)
			)
		)
		(property "Author" "Antmicro"
			(at 373.38 255.27 0)
			(effects
				(font
					(size 1.27 1.27)
					(thickness 0.15)
				)
				(justify left bottom)
				(hide yes)
			)
		)
		(property "License" "Apache-2.0"
			(at 373.38 257.81 0)
			(effects
				(font
					(size 1.27 1.27)
					(thickness 0.15)
				)
				(justify left bottom)
				(hide yes)
			)
		)
		(pin "1"
		)
		(instances
			(project "jetson-agx-thor-baseboard"
				(path ""
					(reference "#PWR0334")
					(unit 1)
				)
			)
		)
	)
	(symbol
		(lib_id "antmicropower:GND")
		(at 271.78 162.56 0)
		(unit 1)
		(exclude_from_sim no)
		(in_bom yes)
		(on_board yes)
		(dnp no)
		(property "Reference" "#PWR0331"
			(at 271.78 168.91 0)
			(effects
				(font
					(size 1.27 1.27)
				)
				(justify left bottom)
				(hide yes)
			)
		)
		(property "Value" "GND"
			(at 271.78 166.37 0)
			(effects
				(font
					(size 1.27 1.27)
					(thickness 0.15)
				)
			)
		)
		(property "Footprint" ""
			(at 280.67 170.18 0)
			(effects
				(font
					(size 1.27 1.27)
					(thickness 0.15)
				)
				(justify left bottom)
				(hide yes)
			)
		)
		(property "Datasheet" ""
			(at 280.67 175.26 0)
			(effects
				(font
					(size 1.27 1.27)
					(thickness 0.15)
				)
				(justify left bottom)
				(hide yes)
			)
		)
		(property "Description" ""
			(at 271.78 162.56 0)
			(effects
				(font
					(size 1.27 1.27)
				)
				(hide yes)
			)
		)
		(property "Author" "Antmicro"
			(at 280.67 170.18 0)
			(effects
				(font
					(size 1.27 1.27)
					(thickness 0.15)
				)
				(justify left bottom)
				(hide yes)
			)
		)
		(property "License" "Apache-2.0"
			(at 280.67 172.72 0)
			(effects
				(font
					(size 1.27 1.27)
					(thickness 0.15)
				)
				(justify left bottom)
				(hide yes)
			)
		)
		(pin "1"
		)
		(instances
			(project "jetson-agx-thor-baseboard"
				(path ""
					(reference "#PWR0331")
					(unit 1)
				)
			)
		)
	)
	(symbol
		(lib_id "antmicropower:+1V8")
		(at 85.09 134.62 0)
		(unit 1)
		(exclude_from_sim no)
		(in_bom yes)
		(on_board yes)
		(dnp no)
		(property "Reference" "#PWR0290"
			(at 85.09 138.43 0)
			(effects
				(font
					(size 1.27 1.27)
				)
				(justify left bottom)
				(hide yes)
			)
		)
		(property "Value" "+1V8"
			(at 84.455 130.81 0)
			(effects
				(font
					(size 1.27 1.27)
					(thickness 0.15)
				)
			)
		)
		(property "Footprint" ""
			(at 100.33 142.24 0)
			(effects
				(font
					(size 1.27 1.27)
					(thickness 0.15)
				)
				(justify left bottom)
				(hide yes)
			)
		)
		(property "Datasheet" ""
			(at 100.33 144.78 0)
			(effects
				(font
					(size 1.27 1.27)
					(thickness 0.15)
				)
				(justify left bottom)
				(hide yes)
			)
		)
		(property "Description" ""
			(at 85.09 134.62 0)
			(effects
				(font
					(size 1.27 1.27)
				)
				(hide yes)
			)
		)
		(property "Author" "Antmicro"
			(at 100.33 139.7 0)
			(effects
				(font
					(size 1.27 1.27)
					(thickness 0.15)
				)
				(justify left bottom)
				(hide yes)
			)
		)
		(property "License" "Apache-2.0"
			(at 100.33 142.24 0)
			(effects
				(font
					(size 1.27 1.27)
					(thickness 0.15)
				)
				(justify left bottom)
				(hide yes)
			)
		)
		(pin "1"
		)
		(instances
			(project "jetson-agx-thor-baseboard"
				(path ""
					(reference "#PWR0290")
					(unit 1)
				)
			)
		)
	)
	(symbol
		(lib_id "antmicroResistors0402:R_0R_0402")
		(at 276.86 137.16 0)
		(mirror y)
		(unit 1)
		(exclude_from_sim no)
		(in_bom yes)
		(on_board yes)
		(dnp no)
		(property "Reference" "R400"
			(at 269.494 136.144 0)
			(effects
				(font
					(size 1.27 1.27)
					(thickness 0.15)
				)
			)
		)
		(property "Value" "R_0R_0402"
			(at 256.54 149.86 0)
			(effects
				(font
					(size 1.27 1.27)
					(thickness 0.15)
				)
				(justify left bottom)
				(hide yes)
			)
		)
		(property "Footprint" "antmicro-footprints:R_0402_1005Metric"
			(at 256.54 152.4 0)
			(effects
				(font
					(size 1.27 1.27)
					(thickness 0.15)
				)
				(justify left bottom)
				(hide yes)
			)
		)
		(property "Datasheet" "https://industrial.panasonic.com/cdbs/www-data/pdf/RDA0000/AOA0000C301.pdf"
			(at 256.54 154.94 0)
			(effects
				(font
					(size 1.27 1.27)
					(thickness 0.15)
				)
				(justify left bottom)
				(hide yes)
			)
		)
		(property "Description" "SMD Chip Resistor, Jumper, 0 ohm, 100 mW, 0402 [1005 Metric], Thick Film, General Purpose"
			(at 256.54 170.18 0)
			(effects
				(font
					(size 1.27 1.27)
				)
				(justify left bottom)
				(hide yes)
			)
		)
		(property "MPN" "ERJ2GE0R00X"
			(at 256.54 157.48 0)
			(effects
				(font
					(size 1.27 1.27)
					(thickness 0.15)
				)
				(justify left bottom)
				(hide yes)
			)
		)
		(property "Manufacturer" "Panasonic"
			(at 256.54 160.02 0)
			(effects
				(font
					(size 1.27 1.27)
					(thickness 0.15)
				)
				(justify left bottom)
				(hide yes)
			)
		)
		(property "License" "Apache-2.0"
			(at 256.54 162.56 0)
			(effects
				(font
					(size 1.27 1.27)
					(thickness 0.15)
				)
				(justify left bottom)
				(hide yes)
			)
		)
		(property "Author" "Antmicro"
			(at 256.54 165.1 0)
			(effects
				(font
					(size 1.27 1.27)
					(thickness 0.15)
				)
				(justify left bottom)
				(hide yes)
			)
		)
		(property "Val" "0R"
			(at 277.622 136.144 0)
			(effects
				(font
					(size 1.27 1.27)
					(thickness 0.15)
				)
			)
		)
		(property "Tolerance" "~"
			(at 256.54 147.32 0)
			(effects
				(font
					(size 1.27 1.27)
				)
				(justify left bottom)
				(hide yes)
			)
		)
		(property "Current" "1A"
			(at 256.54 167.64 0)
			(effects
				(font
					(size 1.27 1.27)
					(thickness 0.15)
				)
				(justify left bottom)
				(hide yes)
			)
		)
		(pin "2"
		)
		(pin "1"
		)
		(instances
			(project "jetson-agx-thor-baseboard"
				(path ""
					(reference "R400")
					(unit 1)
				)
			)
		)
	)
	(symbol
		(lib_id "antmicropower:+3V3")
		(at 113.03 200.66 0)
		(unit 1)
		(exclude_from_sim no)
		(in_bom yes)
		(on_board yes)
		(dnp no)
		(property "Reference" "#PWR0301"
			(at 113.03 204.47 0)
			(effects
				(font
					(size 1.27 1.27)
				)
				(justify left bottom)
				(hide yes)
			)
		)
		(property "Value" "+3V3"
			(at 109.855 196.85 0)
			(effects
				(font
					(size 1.27 1.27)
					(thickness 0.15)
				)
				(justify left)
			)
		)
		(property "Footprint" ""
			(at 128.27 208.28 0)
			(effects
				(font
					(size 1.27 1.27)
					(thickness 0.15)
				)
				(justify left bottom)
				(hide yes)
			)
		)
		(property "Datasheet" ""
			(at 128.27 210.82 0)
			(effects
				(font
					(size 1.27 1.27)
					(thickness 0.15)
				)
				(justify left bottom)
				(hide yes)
			)
		)
		(property "Description" ""
			(at 113.03 200.66 0)
			(effects
				(font
					(size 1.27 1.27)
				)
				(hide yes)
			)
		)
		(property "Author" "Antmicro"
			(at 128.27 203.2 0)
			(effects
				(font
					(size 1.27 1.27)
					(thickness 0.15)
				)
				(justify left bottom)
				(hide yes)
			)
		)
		(property "License" "Apache-2.0"
			(at 128.27 205.74 0)
			(effects
				(font
					(size 1.27 1.27)
					(thickness 0.15)
				)
				(justify left bottom)
				(hide yes)
			)
		)
		(pin "1"
		)
		(instances
			(project "jetson-agx-thor-baseboard"
				(path ""
					(reference "#PWR0301")
					(unit 1)
				)
			)
		)
	)
	(symbol
		(lib_id "antmicropower:GND")
		(at 266.7 162.56 0)
		(unit 1)
		(exclude_from_sim no)
		(in_bom yes)
		(on_board yes)
		(dnp no)
		(property "Reference" "#PWR0330"
			(at 266.7 168.91 0)
			(effects
				(font
					(size 1.27 1.27)
				)
				(justify left bottom)
				(hide yes)
			)
		)
		(property "Value" "GND"
			(at 266.7 166.37 0)
			(effects
				(font
					(size 1.27 1.27)
					(thickness 0.15)
				)
			)
		)
		(property "Footprint" ""
			(at 275.59 170.18 0)
			(effects
				(font
					(size 1.27 1.27)
					(thickness 0.15)
				)
				(justify left bottom)
				(hide yes)
			)
		)
		(property "Datasheet" ""
			(at 275.59 175.26 0)
			(effects
				(font
					(size 1.27 1.27)
					(thickness 0.15)
				)
				(justify left bottom)
				(hide yes)
			)
		)
		(property "Description" ""
			(at 266.7 162.56 0)
			(effects
				(font
					(size 1.27 1.27)
				)
				(hide yes)
			)
		)
		(property "Author" "Antmicro"
			(at 275.59 170.18 0)
			(effects
				(font
					(size 1.27 1.27)
					(thickness 0.15)
				)
				(justify left bottom)
				(hide yes)
			)
		)
		(property "License" "Apache-2.0"
			(at 275.59 172.72 0)
			(effects
				(font
					(size 1.27 1.27)
					(thickness 0.15)
				)
				(justify left bottom)
				(hide yes)
			)
		)
		(pin "1"
		)
		(instances
			(project "jetson-agx-thor-baseboard"
				(path ""
					(reference "#PWR0330")
					(unit 1)
				)
			)
		)
	)
	(symbol
		(lib_id "antmicropower:GND")
		(at 334.01 233.68 0)
		(unit 1)
		(exclude_from_sim no)
		(in_bom yes)
		(on_board yes)
		(dnp no)
		(property "Reference" "#PWR0329"
			(at 334.01 240.03 0)
			(effects
				(font
					(size 1.27 1.27)
				)
				(justify left bottom)
				(hide yes)
			)
		)
		(property "Value" "GND"
			(at 334.01 237.49 0)
			(effects
				(font
					(size 1.27 1.27)
					(thickness 0.15)
				)
			)
		)
		(property "Footprint" ""
			(at 342.9 241.3 0)
			(effects
				(font
					(size 1.27 1.27)
					(thickness 0.15)
				)
				(justify left bottom)
				(hide yes)
			)
		)
		(property "Datasheet" ""
			(at 342.9 246.38 0)
			(effects
				(font
					(size 1.27 1.27)
					(thickness 0.15)
				)
				(justify left bottom)
				(hide yes)
			)
		)
		(property "Description" ""
			(at 334.01 233.68 0)
			(effects
				(font
					(size 1.27 1.27)
				)
				(hide yes)
			)
		)
		(property "Author" "Antmicro"
			(at 342.9 241.3 0)
			(effects
				(font
					(size 1.27 1.27)
					(thickness 0.15)
				)
				(justify left bottom)
				(hide yes)
			)
		)
		(property "License" "Apache-2.0"
			(at 342.9 243.84 0)
			(effects
				(font
					(size 1.27 1.27)
					(thickness 0.15)
				)
				(justify left bottom)
				(hide yes)
			)
		)
		(pin "1"
		)
		(instances
			(project "jetson-agx-thor-baseboard"
				(path ""
					(reference "#PWR0329")
					(unit 1)
				)
			)
		)
	)
	(symbol
		(lib_id "antmicroCapacitors0402:C_1u_0402")
		(at 271.78 161.29 90)
		(unit 1)
		(exclude_from_sim no)
		(in_bom yes)
		(on_board yes)
		(dnp no)
		(fields_autoplaced yes)
		(property "Reference" "C165"
			(at 274.32 157.4736 90)
			(effects
				(font
					(size 1.27 1.27)
				)
				(justify right)
			)
		)
		(property "Value" "C_1u_0402"
			(at 281.94 140.97 0)
			(effects
				(font
					(size 1.27 1.27)
					(thickness 0.15)
				)
				(justify left bottom)
				(hide yes)
			)
		)
		(property "Footprint" "antmicro-footprints:C_0402_1005Metric"
			(at 284.48 140.97 0)
			(effects
				(font
					(size 1.27 1.27)
					(thickness 0.15)
				)
				(justify left bottom)
				(hide yes)
			)
		)
		(property "Datasheet" "https://product.tdk.com/en/search/capacitor/ceramic/mlcc/info?part_no=C1005X6S1A105K050BC"
			(at 287.02 140.97 0)
			(effects
				(font
					(size 1.27 1.27)
					(thickness 0.15)
				)
				(justify left bottom)
				(hide yes)
			)
		)
		(property "Description" "SMD Multilayer Ceramic Capacitor, 1 µF, 10 V, 0402 [1005 Metric], ± 10%, X6S, C"
			(at 271.78 161.29 0)
			(effects
				(font
					(size 1.27 1.27)
				)
				(hide yes)
			)
		)
		(property "Manufacturer" "TDK"
			(at 292.1 140.97 0)
			(effects
				(font
					(size 1.27 1.27)
					(thickness 0.15)
				)
				(justify left bottom)
				(hide yes)
			)
		)
		(property "MPN" "C1005X6S1A105K050BC"
			(at 289.56 140.97 0)
			(effects
				(font
					(size 1.27 1.27)
					(thickness 0.15)
				)
				(justify left bottom)
				(hide yes)
			)
		)
		(property "Val" "1u"
			(at 274.32 160.0136 90)
			(effects
				(font
					(size 1.27 1.27)
					(thickness 0.15)
				)
				(justify right)
			)
		)
		(property "License" "Apache-2.0"
			(at 294.64 140.97 0)
			(effects
				(font
					(size 1.27 1.27)
					(thickness 0.15)
				)
				(justify left bottom)
				(hide yes)
			)
		)
		(property "Author" "Antmicro"
			(at 297.18 140.97 0)
			(effects
				(font
					(size 1.27 1.27)
					(thickness 0.15)
				)
				(justify left bottom)
				(hide yes)
			)
		)
		(property "Voltage" ""
			(at 299.72 140.97 0)
			(effects
				(font
					(size 1.27 1.27)
				)
				(justify left bottom)
				(hide yes)
			)
		)
		(property "Dielectric" ""
			(at 302.26 140.97 0)
			(effects
				(font
					(size 1.27 1.27)
				)
				(justify left bottom)
				(hide yes)
			)
		)
		(pin "1"
		)
		(pin "2"
		)
		(instances
			(project "jetson-agx-thor-baseboard"
				(path ""
					(reference "C165")
					(unit 1)
				)
			)
		)
	)
	(symbol
		(lib_id "antmicroCapacitors0402:C_100n_0402")
		(at 372.11 203.2 270)
		(mirror x)
		(unit 1)
		(exclude_from_sim no)
		(in_bom yes)
		(on_board yes)
		(dnp no)
		(property "Reference" "C166"
			(at 374.015 199.39 90)
			(effects
				(font
					(size 1.27 1.27)
				)
				(justify left)
			)
		)
		(property "Value" "C_100n_0402"
			(at 361.95 182.88 0)
			(effects
				(font
					(size 1.27 1.27)
					(thickness 0.15)
				)
				(justify left bottom)
				(hide yes)
			)
		)
		(property "Footprint" "antmicro-footprints:C_0402_1005Metric"
			(at 359.41 182.88 0)
			(effects
				(font
					(size 1.27 1.27)
					(thickness 0.15)
				)
				(justify left bottom)
				(hide yes)
			)
		)
		(property "Datasheet" "https://www.murata.com/products/productdetail?partno=GRM155R61H104KE14%23"
			(at 356.87 182.88 0)
			(effects
				(font
					(size 1.27 1.27)
					(thickness 0.15)
				)
				(justify left bottom)
				(hide yes)
			)
		)
		(property "Description" "SMD Multilayer Ceramic Capacitor, 0.1 µF, 50 V, 0402 [1005 Metric], ± 10%, X5R, GRM Series"
			(at 372.11 203.2 0)
			(effects
				(font
					(size 1.27 1.27)
				)
				(hide yes)
			)
		)
		(property "Manufacturer" "Murata"
			(at 351.79 182.88 0)
			(effects
				(font
					(size 1.27 1.27)
					(thickness 0.15)
				)
				(justify left bottom)
				(hide yes)
			)
		)
		(property "MPN" "GRM155R61H104KE14D"
			(at 354.33 182.88 0)
			(effects
				(font
					(size 1.27 1.27)
					(thickness 0.15)
				)
				(justify left bottom)
				(hide yes)
			)
		)
		(property "Val" "100n"
			(at 374.015 201.93 90)
			(effects
				(font
					(size 1.27 1.27)
					(thickness 0.15)
				)
				(justify left)
			)
		)
		(property "License" "Apache-2.0"
			(at 349.25 182.88 0)
			(effects
				(font
					(size 1.27 1.27)
					(thickness 0.15)
				)
				(justify left bottom)
				(hide yes)
			)
		)
		(property "Author" "Antmicro"
			(at 346.71 182.88 0)
			(effects
				(font
					(size 1.27 1.27)
					(thickness 0.15)
				)
				(justify left bottom)
				(hide yes)
			)
		)
		(property "Voltage" "50V"
			(at 344.17 182.88 0)
			(effects
				(font
					(size 1.27 1.27)
				)
				(justify left bottom)
				(hide yes)
			)
		)
		(property "Dielectric" "X5R"
			(at 341.63 182.88 0)
			(effects
				(font
					(size 1.27 1.27)
				)
				(justify left bottom)
				(hide yes)
			)
		)
		(pin "1"
		)
		(pin "2"
		)
		(instances
			(project "jetson-agx-thor-baseboard"
				(path ""
					(reference "C166")
					(unit 1)
				)
			)
		)
	)
	(symbol
		(lib_id "antmicropower:GND")
		(at 149.86 220.98 0)
		(unit 1)
		(exclude_from_sim no)
		(in_bom yes)
		(on_board yes)
		(dnp no)
		(property "Reference" "#PWR0306"
			(at 149.86 227.33 0)
			(effects
				(font
					(size 1.27 1.27)
				)
				(justify left bottom)
				(hide yes)
			)
		)
		(property "Value" "GND"
			(at 149.86 224.79 0)
			(effects
				(font
					(size 1.27 1.27)
					(thickness 0.15)
				)
			)
		)
		(property "Footprint" ""
			(at 158.75 228.6 0)
			(effects
				(font
					(size 1.27 1.27)
					(thickness 0.15)
				)
				(justify left bottom)
				(hide yes)
			)
		)
		(property "Datasheet" ""
			(at 158.75 233.68 0)
			(effects
				(font
					(size 1.27 1.27)
					(thickness 0.15)
				)
				(justify left bottom)
				(hide yes)
			)
		)
		(property "Description" ""
			(at 149.86 220.98 0)
			(effects
				(font
					(size 1.27 1.27)
				)
				(hide yes)
			)
		)
		(property "Author" "Antmicro"
			(at 158.75 228.6 0)
			(effects
				(font
					(size 1.27 1.27)
					(thickness 0.15)
				)
				(justify left bottom)
				(hide yes)
			)
		)
		(property "License" "Apache-2.0"
			(at 158.75 231.14 0)
			(effects
				(font
					(size 1.27 1.27)
					(thickness 0.15)
				)
				(justify left bottom)
				(hide yes)
			)
		)
		(pin "1"
		)
		(instances
			(project "jetson-agx-thor-baseboard"
				(path ""
					(reference "#PWR0306")
					(unit 1)
				)
			)
		)
	)
	(symbol
		(lib_id "antmicropower:+3V3")
		(at 222.25 200.66 0)
		(unit 1)
		(exclude_from_sim no)
		(in_bom yes)
		(on_board yes)
		(dnp no)
		(property "Reference" "#PWR0314"
			(at 222.25 204.47 0)
			(effects
				(font
					(size 1.27 1.27)
				)
				(justify left bottom)
				(hide yes)
			)
		)
		(property "Value" "+3V3"
			(at 219.075 196.85 0)
			(effects
				(font
					(size 1.27 1.27)
					(thickness 0.15)
				)
				(justify left)
			)
		)
		(property "Footprint" ""
			(at 237.49 208.28 0)
			(effects
				(font
					(size 1.27 1.27)
					(thickness 0.15)
				)
				(justify left bottom)
				(hide yes)
			)
		)
		(property "Datasheet" ""
			(at 237.49 210.82 0)
			(effects
				(font
					(size 1.27 1.27)
					(thickness 0.15)
				)
				(justify left bottom)
				(hide yes)
			)
		)
		(property "Description" ""
			(at 222.25 200.66 0)
			(effects
				(font
					(size 1.27 1.27)
				)
				(hide yes)
			)
		)
		(property "Author" "Antmicro"
			(at 237.49 203.2 0)
			(effects
				(font
					(size 1.27 1.27)
					(thickness 0.15)
				)
				(justify left bottom)
				(hide yes)
			)
		)
		(property "License" "Apache-2.0"
			(at 237.49 205.74 0)
			(effects
				(font
					(size 1.27 1.27)
					(thickness 0.15)
				)
				(justify left bottom)
				(hide yes)
			)
		)
		(pin "1"
		)
		(instances
			(project "jetson-agx-thor-baseboard"
				(path ""
					(reference "#PWR0314")
					(unit 1)
				)
			)
		)
	)
	(symbol
		(lib_id "antmicropower:GND")
		(at 97.79 256.54 0)
		(unit 1)
		(exclude_from_sim no)
		(in_bom yes)
		(on_board yes)
		(dnp no)
		(property "Reference" "#PWR0292"
			(at 97.79 262.89 0)
			(effects
				(font
					(size 1.27 1.27)
				)
				(justify left bottom)
				(hide yes)
			)
		)
		(property "Value" "GND"
			(at 97.79 260.35 0)
			(effects
				(font
					(size 1.27 1.27)
					(thickness 0.15)
				)
			)
		)
		(property "Footprint" ""
			(at 106.68 264.16 0)
			(effects
				(font
					(size 1.27 1.27)
					(thickness 0.15)
				)
				(justify left bottom)
				(hide yes)
			)
		)
		(property "Datasheet" ""
			(at 106.68 269.24 0)
			(effects
				(font
					(size 1.27 1.27)
					(thickness 0.15)
				)
				(justify left bottom)
				(hide yes)
			)
		)
		(property "Description" ""
			(at 97.79 256.54 0)
			(effects
				(font
					(size 1.27 1.27)
				)
				(hide yes)
			)
		)
		(property "Author" "Antmicro"
			(at 106.68 264.16 0)
			(effects
				(font
					(size 1.27 1.27)
					(thickness 0.15)
				)
				(justify left bottom)
				(hide yes)
			)
		)
		(property "License" "Apache-2.0"
			(at 106.68 266.7 0)
			(effects
				(font
					(size 1.27 1.27)
					(thickness 0.15)
				)
				(justify left bottom)
				(hide yes)
			)
		)
		(pin "1"
		)
		(instances
			(project "jetson-agx-thor-baseboard"
				(path ""
					(reference "#PWR0292")
					(unit 1)
				)
			)
		)
	)
	(symbol
		(lib_id "antmicroResistors0402:R_0R_0402")
		(at 276.86 134.62 0)
		(mirror y)
		(unit 1)
		(exclude_from_sim no)
		(in_bom yes)
		(on_board yes)
		(dnp no)
		(property "Reference" "R399"
			(at 269.494 133.604 0)
			(effects
				(font
					(size 1.27 1.27)
					(thickness 0.15)
				)
			)
		)
		(property "Value" "R_0R_0402"
			(at 256.54 147.32 0)
			(effects
				(font
					(size 1.27 1.27)
					(thickness 0.15)
				)
				(justify left bottom)
				(hide yes)
			)
		)
		(property "Footprint" "antmicro-footprints:R_0402_1005Metric"
			(at 256.54 149.86 0)
			(effects
				(font
					(size 1.27 1.27)
					(thickness 0.15)
				)
				(justify left bottom)
				(hide yes)
			)
		)
		(property "Datasheet" "https://industrial.panasonic.com/cdbs/www-data/pdf/RDA0000/AOA0000C301.pdf"
			(at 256.54 152.4 0)
			(effects
				(font
					(size 1.27 1.27)
					(thickness 0.15)
				)
				(justify left bottom)
				(hide yes)
			)
		)
		(property "Description" "SMD Chip Resistor, Jumper, 0 ohm, 100 mW, 0402 [1005 Metric], Thick Film, General Purpose"
			(at 256.54 167.64 0)
			(effects
				(font
					(size 1.27 1.27)
				)
				(justify left bottom)
				(hide yes)
			)
		)
		(property "MPN" "ERJ2GE0R00X"
			(at 256.54 154.94 0)
			(effects
				(font
					(size 1.27 1.27)
					(thickness 0.15)
				)
				(justify left bottom)
				(hide yes)
			)
		)
		(property "Manufacturer" "Panasonic"
			(at 256.54 157.48 0)
			(effects
				(font
					(size 1.27 1.27)
					(thickness 0.15)
				)
				(justify left bottom)
				(hide yes)
			)
		)
		(property "License" "Apache-2.0"
			(at 256.54 160.02 0)
			(effects
				(font
					(size 1.27 1.27)
					(thickness 0.15)
				)
				(justify left bottom)
				(hide yes)
			)
		)
		(property "Author" "Antmicro"
			(at 256.54 162.56 0)
			(effects
				(font
					(size 1.27 1.27)
					(thickness 0.15)
				)
				(justify left bottom)
				(hide yes)
			)
		)
		(property "Val" "0R"
			(at 277.622 133.604 0)
			(effects
				(font
					(size 1.27 1.27)
					(thickness 0.15)
				)
			)
		)
		(property "Tolerance" "~"
			(at 256.54 144.78 0)
			(effects
				(font
					(size 1.27 1.27)
				)
				(justify left bottom)
				(hide yes)
			)
		)
		(property "Current" "1A"
			(at 256.54 165.1 0)
			(effects
				(font
					(size 1.27 1.27)
					(thickness 0.15)
				)
				(justify left bottom)
				(hide yes)
			)
		)
		(pin "2"
		)
		(pin "1"
		)
		(instances
			(project "jetson-agx-thor-baseboard"
				(path ""
					(reference "R399")
					(unit 1)
				)
			)
		)
	)
	(symbol
		(lib_id "antmicroLEDIndicationDiscrete:LED_G_0603_LTST-C190GKT")
		(at 251.46 167.64 90)
		(unit 1)
		(exclude_from_sim no)
		(in_bom yes)
		(on_board yes)
		(dnp no)
		(fields_autoplaced yes)
		(property "Reference" "D29"
			(at 254 163.83 90)
			(effects
				(font
					(size 1.27 1.27)
				)
				(justify right)
			)
		)
		(property "Value" "LED_G_0603_LTST-C190GKT"
			(at 259.08 144.78 0)
			(effects
				(font
					(size 1.27 1.27)
					(thickness 0.15)
				)
				(justify left bottom)
				(hide yes)
			)
		)
		(property "Footprint" "antmicro-footprints:LED_0603_1608Metric_G"
			(at 261.62 144.78 0)
			(effects
				(font
					(size 1.27 1.27)
					(thickness 0.15)
				)
				(justify left bottom)
				(hide yes)
			)
		)
		(property "Datasheet" "https://media.digikey.com/pdf/Data%20Sheets/Lite-On%20PDFs/LTST-C190GKT.pdf"
			(at 264.16 144.78 0)
			(effects
				(font
					(size 1.27 1.27)
					(thickness 0.15)
				)
				(justify left bottom)
				(hide yes)
			)
		)
		(property "Description" "LED, Green, SMD, 0603, 20 mA, 2.1 V, 569 nm"
			(at 251.46 167.64 0)
			(effects
				(font
					(size 1.27 1.27)
				)
				(hide yes)
			)
		)
		(property "MPN" "LTST-C190GKT"
			(at 266.7 144.78 0)
			(effects
				(font
					(size 1.27 1.27)
					(thickness 0.15)
				)
				(justify left bottom)
				(hide yes)
			)
		)
		(property "Manufacturer" "Lite-On"
			(at 269.24 144.78 0)
			(effects
				(font
					(size 1.27 1.27)
					(thickness 0.15)
				)
				(justify left bottom)
				(hide yes)
			)
		)
		(property "Author" "Antmicro"
			(at 271.78 144.78 0)
			(effects
				(font
					(size 1.27 1.27)
					(thickness 0.15)
				)
				(justify left bottom)
				(hide yes)
			)
		)
		(property "License" "Apache-2.0"
			(at 274.32 144.78 0)
			(effects
				(font
					(size 1.27 1.27)
					(thickness 0.15)
				)
				(justify left bottom)
				(hide yes)
			)
		)
		(property "Color" "Green"
			(at 254 166.37 90)
			(effects
				(font
					(size 1.27 1.27)
				)
				(justify right)
			)
		)
		(pin "1"
		)
		(pin "2"
		)
		(instances
			(project "jetson-agx-thor-baseboard"
				(path ""
					(reference "D29")
					(unit 1)
				)
			)
		)
	)
	(symbol
		(lib_id "antmicroResistors0402:R_2k2_0402")
		(at 91.44 151.13 270)
		(unit 1)
		(exclude_from_sim no)
		(in_bom yes)
		(on_board yes)
		(dnp no)
		(property "Reference" "R389"
			(at 90.424 146.558 0)
			(effects
				(font
					(size 1.27 1.27)
					(thickness 0.15)
				)
				(justify left)
			)
		)
		(property "Value" "R_2k2_0402"
			(at 78.74 171.45 0)
			(effects
				(font
					(size 1.27 1.27)
					(thickness 0.15)
				)
				(justify left bottom)
				(hide yes)
			)
		)
		(property "Footprint" "antmicro-footprints:R_0402_1005Metric"
			(at 76.2 171.45 0)
			(effects
				(font
					(size 1.27 1.27)
					(thickness 0.15)
				)
				(justify left bottom)
				(hide yes)
			)
		)
		(property "Datasheet" "https://www.bourns.com/docs/product-datasheets/cr.pdf"
			(at 73.66 171.45 0)
			(effects
				(font
					(size 1.27 1.27)
					(thickness 0.15)
				)
				(justify left bottom)
				(hide yes)
			)
		)
		(property "Description" "SMD Chip Resistor, 2.2 kohm, ± 1%, 62.5 mW, 0402 [1005 Metric], Thick Film, General Purpose"
			(at 60.96 171.45 0)
			(effects
				(font
					(size 1.27 1.27)
				)
				(justify left bottom)
				(hide yes)
			)
		)
		(property "MPN" "CR0402-FX-2201GLF"
			(at 71.12 171.45 0)
			(effects
				(font
					(size 1.27 1.27)
					(thickness 0.15)
				)
				(justify left bottom)
				(hide yes)
			)
		)
		(property "Manufacturer" "Bourns"
			(at 68.58 171.45 0)
			(effects
				(font
					(size 1.27 1.27)
					(thickness 0.15)
				)
				(justify left bottom)
				(hide yes)
			)
		)
		(property "License" "Apache-2.0"
			(at 66.04 171.45 0)
			(effects
				(font
					(size 1.27 1.27)
					(thickness 0.15)
				)
				(justify left bottom)
				(hide yes)
			)
		)
		(property "Author" "Antmicro"
			(at 63.5 171.45 0)
			(effects
				(font
					(size 1.27 1.27)
					(thickness 0.15)
				)
				(justify left bottom)
				(hide yes)
			)
		)
		(property "Val" "2k2"
			(at 90.424 155.702 0)
			(effects
				(font
					(size 1.27 1.27)
					(thickness 0.15)
				)
				(justify left)
			)
		)
		(property "Tolerance" "1%"
			(at 81.28 171.45 0)
			(effects
				(font
					(size 1.27 1.27)
				)
				(justify left bottom)
				(hide yes)
			)
		)
		(pin "1"
		)
		(pin "2"
		)
		(instances
			(project ""
				(path ""
					(reference "R389")
					(unit 1)
				)
			)
		)
	)
	(symbol
		(lib_id "antmicropower:GND")
		(at 323.85 168.91 0)
		(unit 1)
		(exclude_from_sim no)
		(in_bom yes)
		(on_board yes)
		(dnp no)
		(property "Reference" "#PWR0317"
			(at 323.85 175.26 0)
			(effects
				(font
					(size 1.27 1.27)
				)
				(justify left bottom)
				(hide yes)
			)
		)
		(property "Value" "GND"
			(at 323.85 172.72 0)
			(effects
				(font
					(size 1.27 1.27)
					(thickness 0.15)
				)
			)
		)
		(property "Footprint" ""
			(at 332.74 176.53 0)
			(effects
				(font
					(size 1.27 1.27)
					(thickness 0.15)
				)
				(justify left bottom)
				(hide yes)
			)
		)
		(property "Datasheet" ""
			(at 332.74 181.61 0)
			(effects
				(font
					(size 1.27 1.27)
					(thickness 0.15)
				)
				(justify left bottom)
				(hide yes)
			)
		)
		(property "Description" ""
			(at 323.85 168.91 0)
			(effects
				(font
					(size 1.27 1.27)
				)
				(hide yes)
			)
		)
		(property "Author" "Antmicro"
			(at 332.74 176.53 0)
			(effects
				(font
					(size 1.27 1.27)
					(thickness 0.15)
				)
				(justify left bottom)
				(hide yes)
			)
		)
		(property "License" "Apache-2.0"
			(at 332.74 179.07 0)
			(effects
				(font
					(size 1.27 1.27)
					(thickness 0.15)
				)
				(justify left bottom)
				(hide yes)
			)
		)
		(pin "1"
		)
		(instances
			(project "jetson-agx-thor-baseboard"
				(path ""
					(reference "#PWR0317")
					(unit 1)
				)
			)
		)
	)
	(symbol
		(lib_id "antmicroResistors0402:R_0R_0402")
		(at 276.86 132.08 0)
		(mirror y)
		(unit 1)
		(exclude_from_sim no)
		(in_bom yes)
		(on_board yes)
		(dnp no)
		(property "Reference" "R184"
			(at 269.494 131.064 0)
			(effects
				(font
					(size 1.27 1.27)
					(thickness 0.15)
				)
			)
		)
		(property "Value" "R_0R_0402"
			(at 256.54 144.78 0)
			(effects
				(font
					(size 1.27 1.27)
					(thickness 0.15)
				)
				(justify left bottom)
				(hide yes)
			)
		)
		(property "Footprint" "antmicro-footprints:R_0402_1005Metric"
			(at 256.54 147.32 0)
			(effects
				(font
					(size 1.27 1.27)
					(thickness 0.15)
				)
				(justify left bottom)
				(hide yes)
			)
		)
		(property "Datasheet" "https://industrial.panasonic.com/cdbs/www-data/pdf/RDA0000/AOA0000C301.pdf"
			(at 256.54 149.86 0)
			(effects
				(font
					(size 1.27 1.27)
					(thickness 0.15)
				)
				(justify left bottom)
				(hide yes)
			)
		)
		(property "Description" "SMD Chip Resistor, Jumper, 0 ohm, 100 mW, 0402 [1005 Metric], Thick Film, General Purpose"
			(at 256.54 165.1 0)
			(effects
				(font
					(size 1.27 1.27)
				)
				(justify left bottom)
				(hide yes)
			)
		)
		(property "MPN" "ERJ2GE0R00X"
			(at 256.54 152.4 0)
			(effects
				(font
					(size 1.27 1.27)
					(thickness 0.15)
				)
				(justify left bottom)
				(hide yes)
			)
		)
		(property "Manufacturer" "Panasonic"
			(at 256.54 154.94 0)
			(effects
				(font
					(size 1.27 1.27)
					(thickness 0.15)
				)
				(justify left bottom)
				(hide yes)
			)
		)
		(property "License" "Apache-2.0"
			(at 256.54 157.48 0)
			(effects
				(font
					(size 1.27 1.27)
					(thickness 0.15)
				)
				(justify left bottom)
				(hide yes)
			)
		)
		(property "Author" "Antmicro"
			(at 256.54 160.02 0)
			(effects
				(font
					(size 1.27 1.27)
					(thickness 0.15)
				)
				(justify left bottom)
				(hide yes)
			)
		)
		(property "Val" "0R"
			(at 277.622 131.064 0)
			(effects
				(font
					(size 1.27 1.27)
					(thickness 0.15)
				)
			)
		)
		(property "Tolerance" "~"
			(at 256.54 142.24 0)
			(effects
				(font
					(size 1.27 1.27)
				)
				(justify left bottom)
				(hide yes)
			)
		)
		(property "Current" "1A"
			(at 256.54 162.56 0)
			(effects
				(font
					(size 1.27 1.27)
					(thickness 0.15)
				)
				(justify left bottom)
				(hide yes)
			)
		)
		(pin "2"
		)
		(pin "1"
		)
		(instances
			(project "jetson-agx-thor-baseboard"
				(path ""
					(reference "R184")
					(unit 1)
				)
			)
		)
	)
	(symbol
		(lib_id "antmicroCapacitors0402:C_100n_0402")
		(at 334.01 232.41 270)
		(mirror x)
		(unit 1)
		(exclude_from_sim no)
		(in_bom yes)
		(on_board yes)
		(dnp no)
		(property "Reference" "C163"
			(at 332.105 228.6 90)
			(effects
				(font
					(size 1.27 1.27)
				)
				(justify right)
			)
		)
		(property "Value" "C_100n_0402"
			(at 323.85 212.09 0)
			(effects
				(font
					(size 1.27 1.27)
					(thickness 0.15)
				)
				(justify left bottom)
				(hide yes)
			)
		)
		(property "Footprint" "antmicro-footprints:C_0402_1005Metric"
			(at 321.31 212.09 0)
			(effects
				(font
					(size 1.27 1.27)
					(thickness 0.15)
				)
				(justify left bottom)
				(hide yes)
			)
		)
		(property "Datasheet" "https://www.murata.com/products/productdetail?partno=GRM155R61H104KE14%23"
			(at 318.77 212.09 0)
			(effects
				(font
					(size 1.27 1.27)
					(thickness 0.15)
				)
				(justify left bottom)
				(hide yes)
			)
		)
		(property "Description" "SMD Multilayer Ceramic Capacitor, 0.1 µF, 50 V, 0402 [1005 Metric], ± 10%, X5R, GRM Series"
			(at 334.01 232.41 0)
			(effects
				(font
					(size 1.27 1.27)
				)
				(hide yes)
			)
		)
		(property "Manufacturer" "Murata"
			(at 313.69 212.09 0)
			(effects
				(font
					(size 1.27 1.27)
					(thickness 0.15)
				)
				(justify left bottom)
				(hide yes)
			)
		)
		(property "MPN" "GRM155R61H104KE14D"
			(at 316.23 212.09 0)
			(effects
				(font
					(size 1.27 1.27)
					(thickness 0.15)
				)
				(justify left bottom)
				(hide yes)
			)
		)
		(property "Val" "100n"
			(at 332.105 231.14 90)
			(effects
				(font
					(size 1.27 1.27)
					(thickness 0.15)
				)
				(justify right)
			)
		)
		(property "License" "Apache-2.0"
			(at 311.15 212.09 0)
			(effects
				(font
					(size 1.27 1.27)
					(thickness 0.15)
				)
				(justify left bottom)
				(hide yes)
			)
		)
		(property "Author" "Antmicro"
			(at 308.61 212.09 0)
			(effects
				(font
					(size 1.27 1.27)
					(thickness 0.15)
				)
				(justify left bottom)
				(hide yes)
			)
		)
		(property "Voltage" "50V"
			(at 306.07 212.09 0)
			(effects
				(font
					(size 1.27 1.27)
				)
				(justify left bottom)
				(hide yes)
			)
		)
		(property "Dielectric" "X5R"
			(at 303.53 212.09 0)
			(effects
				(font
					(size 1.27 1.27)
				)
				(justify left bottom)
				(hide yes)
			)
		)
		(pin "1"
		)
		(pin "2"
		)
		(instances
			(project "jetson-agx-thor-baseboard"
				(path ""
					(reference "C163")
					(unit 1)
				)
			)
		)
	)
	(symbol
		(lib_id "antmicroResistors0402:R_2k2_0402")
		(at 135.89 151.13 270)
		(unit 1)
		(exclude_from_sim no)
		(in_bom yes)
		(on_board yes)
		(dnp no)
		(property "Reference" "R394"
			(at 134.874 146.558 0)
			(effects
				(font
					(size 1.27 1.27)
					(thickness 0.15)
				)
				(justify left)
			)
		)
		(property "Value" "R_2k2_0402"
			(at 123.19 171.45 0)
			(effects
				(font
					(size 1.27 1.27)
					(thickness 0.15)
				)
				(justify left bottom)
				(hide yes)
			)
		)
		(property "Footprint" "antmicro-footprints:R_0402_1005Metric"
			(at 120.65 171.45 0)
			(effects
				(font
					(size 1.27 1.27)
					(thickness 0.15)
				)
				(justify left bottom)
				(hide yes)
			)
		)
		(property "Datasheet" "https://www.bourns.com/docs/product-datasheets/cr.pdf"
			(at 118.11 171.45 0)
			(effects
				(font
					(size 1.27 1.27)
					(thickness 0.15)
				)
				(justify left bottom)
				(hide yes)
			)
		)
		(property "Description" "SMD Chip Resistor, 2.2 kohm, ± 1%, 62.5 mW, 0402 [1005 Metric], Thick Film, General Purpose"
			(at 105.41 171.45 0)
			(effects
				(font
					(size 1.27 1.27)
				)
				(justify left bottom)
				(hide yes)
			)
		)
		(property "MPN" "CR0402-FX-2201GLF"
			(at 115.57 171.45 0)
			(effects
				(font
					(size 1.27 1.27)
					(thickness 0.15)
				)
				(justify left bottom)
				(hide yes)
			)
		)
		(property "Manufacturer" "Bourns"
			(at 113.03 171.45 0)
			(effects
				(font
					(size 1.27 1.27)
					(thickness 0.15)
				)
				(justify left bottom)
				(hide yes)
			)
		)
		(property "License" "Apache-2.0"
			(at 110.49 171.45 0)
			(effects
				(font
					(size 1.27 1.27)
					(thickness 0.15)
				)
				(justify left bottom)
				(hide yes)
			)
		)
		(property "Author" "Antmicro"
			(at 107.95 171.45 0)
			(effects
				(font
					(size 1.27 1.27)
					(thickness 0.15)
				)
				(justify left bottom)
				(hide yes)
			)
		)
		(property "Val" "2k2"
			(at 134.874 155.702 0)
			(effects
				(font
					(size 1.27 1.27)
					(thickness 0.15)
				)
				(justify left)
			)
		)
		(property "Tolerance" "1%"
			(at 125.73 171.45 0)
			(effects
				(font
					(size 1.27 1.27)
				)
				(justify left bottom)
				(hide yes)
			)
		)
		(pin "1"
		)
		(pin "2"
		)
		(instances
			(project "jetson-agx-thor-baseboard"
				(path ""
					(reference "R394")
					(unit 1)
				)
			)
		)
	)
	(symbol
		(lib_id "antmicropower:+1V8")
		(at 334.01 195.58 0)
		(unit 1)
		(exclude_from_sim no)
		(in_bom yes)
		(on_board yes)
		(dnp no)
		(property "Reference" "#PWR0326"
			(at 334.01 199.39 0)
			(effects
				(font
					(size 1.27 1.27)
				)
				(justify left bottom)
				(hide yes)
			)
		)
		(property "Value" "+1V8"
			(at 330.835 191.77 0)
			(effects
				(font
					(size 1.27 1.27)
					(thickness 0.15)
				)
				(justify left)
			)
		)
		(property "Footprint" ""
			(at 349.25 203.2 0)
			(effects
				(font
					(size 1.27 1.27)
					(thickness 0.15)
				)
				(justify left bottom)
				(hide yes)
			)
		)
		(property "Datasheet" ""
			(at 349.25 205.74 0)
			(effects
				(font
					(size 1.27 1.27)
					(thickness 0.15)
				)
				(justify left bottom)
				(hide yes)
			)
		)
		(property "Description" ""
			(at 334.01 195.58 0)
			(effects
				(font
					(size 1.27 1.27)
				)
				(hide yes)
			)
		)
		(property "Author" "Antmicro"
			(at 349.25 200.66 0)
			(effects
				(font
					(size 1.27 1.27)
					(thickness 0.15)
				)
				(justify left bottom)
				(hide yes)
			)
		)
		(property "License" "Apache-2.0"
			(at 349.25 203.2 0)
			(effects
				(font
					(size 1.27 1.27)
					(thickness 0.15)
				)
				(justify left bottom)
				(hide yes)
			)
		)
		(pin "1"
		)
		(instances
			(project "jetson-agx-thor-baseboard"
				(path ""
					(reference "#PWR0326")
					(unit 1)
				)
			)
		)
	)
	(symbol
		(lib_id "antmicroResistors0402:R_0R_0402")
		(at 85.09 87.63 90)
		(unit 1)
		(exclude_from_sim no)
		(in_bom no)
		(on_board yes)
		(dnp yes)
		(property "Reference" "R159"
			(at 86.36 83.82 90)
			(effects
				(font
					(size 1.27 1.27)
				)
				(justify right)
			)
		)
		(property "Value" "R_0R_0402"
			(at 97.79 67.31 0)
			(effects
				(font
					(size 1.27 1.27)
					(thickness 0.15)
				)
				(justify left bottom)
				(hide yes)
			)
		)
		(property "Footprint" "antmicro-footprints:R_0402_1005Metric"
			(at 100.33 67.31 0)
			(effects
				(font
					(size 1.27 1.27)
					(thickness 0.15)
				)
				(justify left bottom)
				(hide yes)
			)
		)
		(property "Datasheet" "https://industrial.panasonic.com/cdbs/www-data/pdf/RDA0000/AOA0000C301.pdf"
			(at 102.87 67.31 0)
			(effects
				(font
					(size 1.27 1.27)
					(thickness 0.15)
				)
				(justify left bottom)
				(hide yes)
			)
		)
		(property "Description" "SMD Chip Resistor, Jumper, 0 ohm, 100 mW, 0402 [1005 Metric], Thick Film, General Purpose"
			(at 85.09 87.63 0)
			(effects
				(font
					(size 1.27 1.27)
				)
				(hide yes)
			)
		)
		(property "Manufacturer" "Panasonic"
			(at 107.95 67.31 0)
			(effects
				(font
					(size 1.27 1.27)
					(thickness 0.15)
				)
				(justify left bottom)
				(hide yes)
			)
		)
		(property "MPN" "ERJ2GE0R00X"
			(at 105.41 67.31 0)
			(effects
				(font
					(size 1.27 1.27)
					(thickness 0.15)
				)
				(justify left bottom)
				(hide yes)
			)
		)
		(property "Val" "0R"
			(at 86.36 86.36 90)
			(effects
				(font
					(size 1.27 1.27)
					(thickness 0.15)
				)
				(justify right)
			)
		)
		(property "License" "Apache-2.0"
			(at 110.49 67.31 0)
			(effects
				(font
					(size 1.27 1.27)
					(thickness 0.15)
				)
				(justify left bottom)
				(hide yes)
			)
		)
		(property "Author" "Antmicro"
			(at 113.03 67.31 0)
			(effects
				(font
					(size 1.27 1.27)
					(thickness 0.15)
				)
				(justify left bottom)
				(hide yes)
			)
		)
		(property "Tolerance" "~"
			(at 95.25 67.31 0)
			(effects
				(font
					(size 1.27 1.27)
				)
				(justify left bottom)
				(hide yes)
			)
		)
		(property "Current" "1A"
			(at 115.57 67.31 0)
			(effects
				(font
					(size 1.27 1.27)
					(thickness 0.15)
				)
				(justify left bottom)
				(hide yes)
			)
		)
		(pin "1"
		)
		(pin "2"
		)
		(instances
			(project "jetson-agx-thor-baseboard"
				(path ""
					(reference "R159")
					(unit 1)
				)
			)
		)
	)
	(symbol
		(lib_id "antmicroTestPoints:TP_0.75mm_SMD")
		(at 147.32 106.68 0)
		(unit 1)
		(exclude_from_sim no)
		(in_bom no)
		(on_board yes)
		(dnp no)
		(property "Reference" "TP27"
			(at 153.67 106.68 0)
			(effects
				(font
					(size 1.27 1.27)
				)
			)
		)
		(property "Value" "TP_0.75mm_SMD"
			(at 157.48 110.49 0)
			(effects
				(font
					(size 1.27 1.27)
					(thickness 0.15)
				)
				(justify left bottom)
				(hide yes)
			)
		)
		(property "Footprint" "antmicro-footprints:TP_SMD_0.75mm"
			(at 157.48 113.03 0)
			(effects
				(font
					(size 1.27 1.27)
					(thickness 0.15)
				)
				(justify left bottom)
				(hide yes)
			)
		)
		(property "Datasheet" ""
			(at 165.1 119.38 0)
			(effects
				(font
					(size 1.27 1.27)
					(thickness 0.15)
				)
				(justify left bottom)
				(hide yes)
			)
		)
		(property "Description" "SMT test point"
			(at 147.32 106.68 0)
			(effects
				(font
					(size 1.27 1.27)
				)
				(hide yes)
			)
		)
		(property "MPN" ""
			(at 158.115 118.11 0)
			(effects
				(font
					(size 1.27 1.27)
					(thickness 0.15)
				)
				(justify left bottom)
				(hide yes)
			)
		)
		(property "Manufacturer" ""
			(at 158.115 113.03 0)
			(effects
				(font
					(size 1.27 1.27)
					(thickness 0.15)
				)
				(justify left bottom)
				(hide yes)
			)
		)
		(property "Author" "Antmicro"
			(at 157.48 115.57 0)
			(effects
				(font
					(size 1.27 1.27)
					(thickness 0.15)
				)
				(justify left bottom)
				(hide yes)
			)
		)
		(property "License" "Apache-2.0"
			(at 157.48 118.11 0)
			(effects
				(font
					(size 1.27 1.27)
					(thickness 0.15)
				)
				(justify left bottom)
				(hide yes)
			)
		)
		(pin "1"
		)
		(instances
			(project "jetson-agx-thor-baseboard"
				(path ""
					(reference "TP27")
					(unit 1)
				)
			)
		)
	)
	(symbol
		(lib_id "antmicropower:GND")
		(at 102.87 209.55 0)
		(unit 1)
		(exclude_from_sim no)
		(in_bom yes)
		(on_board yes)
		(dnp no)
		(property "Reference" "#PWR0297"
			(at 102.87 215.9 0)
			(effects
				(font
					(size 1.27 1.27)
				)
				(justify left bottom)
				(hide yes)
			)
		)
		(property "Value" "GND"
			(at 102.87 213.36 0)
			(effects
				(font
					(size 1.27 1.27)
					(thickness 0.15)
				)
			)
		)
		(property "Footprint" ""
			(at 111.76 217.17 0)
			(effects
				(font
					(size 1.27 1.27)
					(thickness 0.15)
				)
				(justify left bottom)
				(hide yes)
			)
		)
		(property "Datasheet" ""
			(at 111.76 222.25 0)
			(effects
				(font
					(size 1.27 1.27)
					(thickness 0.15)
				)
				(justify left bottom)
				(hide yes)
			)
		)
		(property "Description" ""
			(at 102.87 209.55 0)
			(effects
				(font
					(size 1.27 1.27)
				)
				(hide yes)
			)
		)
		(property "Author" "Antmicro"
			(at 111.76 217.17 0)
			(effects
				(font
					(size 1.27 1.27)
					(thickness 0.15)
				)
				(justify left bottom)
				(hide yes)
			)
		)
		(property "License" "Apache-2.0"
			(at 111.76 219.71 0)
			(effects
				(font
					(size 1.27 1.27)
					(thickness 0.15)
				)
				(justify left bottom)
				(hide yes)
			)
		)
		(pin "1"
		)
		(instances
			(project "jetson-agx-thor-baseboard"
				(path ""
					(reference "#PWR0297")
					(unit 1)
				)
			)
		)
	)
	(symbol
		(lib_id "antmicroCapacitors0402:C_100n_0402")
		(at 212.09 234.95 90)
		(mirror x)
		(unit 1)
		(exclude_from_sim no)
		(in_bom yes)
		(on_board yes)
		(dnp no)
		(property "Reference" "C159"
			(at 213.995 236.22 90)
			(effects
				(font
					(size 1.27 1.27)
				)
				(justify right)
			)
		)
		(property "Value" "C_100n_0402"
			(at 222.25 255.27 0)
			(effects
				(font
					(size 1.27 1.27)
					(thickness 0.15)
				)
				(justify left bottom)
				(hide yes)
			)
		)
		(property "Footprint" "antmicro-footprints:C_0402_1005Metric"
			(at 224.79 255.27 0)
			(effects
				(font
					(size 1.27 1.27)
					(thickness 0.15)
				)
				(justify left bottom)
				(hide yes)
			)
		)
		(property "Datasheet" "https://www.murata.com/products/productdetail?partno=GRM155R61H104KE14%23"
			(at 227.33 255.27 0)
			(effects
				(font
					(size 1.27 1.27)
					(thickness 0.15)
				)
				(justify left bottom)
				(hide yes)
			)
		)
		(property "Description" "SMD Multilayer Ceramic Capacitor, 0.1 µF, 50 V, 0402 [1005 Metric], ± 10%, X5R, GRM Series"
			(at 212.09 234.95 0)
			(effects
				(font
					(size 1.27 1.27)
				)
				(hide yes)
			)
		)
		(property "Manufacturer" "Murata"
			(at 232.41 255.27 0)
			(effects
				(font
					(size 1.27 1.27)
					(thickness 0.15)
				)
				(justify left bottom)
				(hide yes)
			)
		)
		(property "MPN" "GRM155R61H104KE14D"
			(at 229.87 255.27 0)
			(effects
				(font
					(size 1.27 1.27)
					(thickness 0.15)
				)
				(justify left bottom)
				(hide yes)
			)
		)
		(property "Val" "100n"
			(at 213.995 238.76 90)
			(effects
				(font
					(size 1.27 1.27)
					(thickness 0.15)
				)
				(justify right)
			)
		)
		(property "License" "Apache-2.0"
			(at 234.95 255.27 0)
			(effects
				(font
					(size 1.27 1.27)
					(thickness 0.15)
				)
				(justify left bottom)
				(hide yes)
			)
		)
		(property "Author" "Antmicro"
			(at 237.49 255.27 0)
			(effects
				(font
					(size 1.27 1.27)
					(thickness 0.15)
				)
				(justify left bottom)
				(hide yes)
			)
		)
		(property "Voltage" "50V"
			(at 240.03 255.27 0)
			(effects
				(font
					(size 1.27 1.27)
				)
				(justify left bottom)
				(hide yes)
			)
		)
		(property "Dielectric" "X5R"
			(at 242.57 255.27 0)
			(effects
				(font
					(size 1.27 1.27)
				)
				(justify left bottom)
				(hide yes)
			)
		)
		(pin "1"
		)
		(pin "2"
		)
		(instances
			(project "jetson-agx-thor-baseboard"
				(path ""
					(reference "C159")
					(unit 1)
				)
			)
		)
	)
	(symbol
		(lib_id "antmicroResistors0402:R_470R_0402")
		(at 251.46 161.29 90)
		(unit 1)
		(exclude_from_sim no)
		(in_bom yes)
		(on_board yes)
		(dnp no)
		(fields_autoplaced yes)
		(property "Reference" "R183"
			(at 253.365 157.48 90)
			(effects
				(font
					(size 1.27 1.27)
				)
				(justify right)
			)
		)
		(property "Value" "R_470R_0402"
			(at 264.16 140.97 0)
			(effects
				(font
					(size 1.27 1.27)
					(thickness 0.15)
				)
				(justify left bottom)
				(hide yes)
			)
		)
		(property "Footprint" "antmicro-footprints:R_0402_1005Metric"
			(at 266.7 140.97 0)
			(effects
				(font
					(size 1.27 1.27)
					(thickness 0.15)
				)
				(justify left bottom)
				(hide yes)
			)
		)
		(property "Datasheet" "https://www.bourns.com/docs/product-datasheets/cr.pdf"
			(at 269.24 140.97 0)
			(effects
				(font
					(size 1.27 1.27)
					(thickness 0.15)
				)
				(justify left bottom)
				(hide yes)
			)
		)
		(property "Description" "SMD Chip Resistor, 470 ohm, ± 1%, 62.5 mW, 0402 [1005 Metric], Thick Film, General Purpose"
			(at 251.46 161.29 0)
			(effects
				(font
					(size 1.27 1.27)
				)
				(hide yes)
			)
		)
		(property "Manufacturer" "Bourns"
			(at 274.32 140.97 0)
			(effects
				(font
					(size 1.27 1.27)
					(thickness 0.15)
				)
				(justify left bottom)
				(hide yes)
			)
		)
		(property "MPN" "CR0402-FX-4700GLF"
			(at 271.78 140.97 0)
			(effects
				(font
					(size 1.27 1.27)
					(thickness 0.15)
				)
				(justify left bottom)
				(hide yes)
			)
		)
		(property "Val" "470R"
			(at 253.365 160.02 90)
			(effects
				(font
					(size 1.27 1.27)
					(thickness 0.15)
				)
				(justify right)
			)
		)
		(property "License" "Apache-2.0"
			(at 276.86 140.97 0)
			(effects
				(font
					(size 1.27 1.27)
					(thickness 0.15)
				)
				(justify left bottom)
				(hide yes)
			)
		)
		(property "Author" "Antmicro"
			(at 279.4 140.97 0)
			(effects
				(font
					(size 1.27 1.27)
					(thickness 0.15)
				)
				(justify left bottom)
				(hide yes)
			)
		)
		(property "Tolerance" "1%"
			(at 261.62 140.97 0)
			(effects
				(font
					(size 1.27 1.27)
				)
				(justify left bottom)
				(hide yes)
			)
		)
		(pin "1"
		)
		(pin "2"
		)
		(instances
			(project "jetson-agx-thor-baseboard"
				(path ""
					(reference "R183")
					(unit 1)
				)
			)
		)
	)
	(symbol
		(lib_id "antmicropower:GND")
		(at 259.08 220.98 0)
		(unit 1)
		(exclude_from_sim no)
		(in_bom yes)
		(on_board yes)
		(dnp no)
		(property "Reference" "#PWR0319"
			(at 259.08 227.33 0)
			(effects
				(font
					(size 1.27 1.27)
				)
				(justify left bottom)
				(hide yes)
			)
		)
		(property "Value" "GND"
			(at 259.08 224.79 0)
			(effects
				(font
					(size 1.27 1.27)
					(thickness 0.15)
				)
			)
		)
		(property "Footprint" ""
			(at 267.97 228.6 0)
			(effects
				(font
					(size 1.27 1.27)
					(thickness 0.15)
				)
				(justify left bottom)
				(hide yes)
			)
		)
		(property "Datasheet" ""
			(at 267.97 233.68 0)
			(effects
				(font
					(size 1.27 1.27)
					(thickness 0.15)
				)
				(justify left bottom)
				(hide yes)
			)
		)
		(property "Description" ""
			(at 259.08 220.98 0)
			(effects
				(font
					(size 1.27 1.27)
				)
				(hide yes)
			)
		)
		(property "Author" "Antmicro"
			(at 267.97 228.6 0)
			(effects
				(font
					(size 1.27 1.27)
					(thickness 0.15)
				)
				(justify left bottom)
				(hide yes)
			)
		)
		(property "License" "Apache-2.0"
			(at 267.97 231.14 0)
			(effects
				(font
					(size 1.27 1.27)
					(thickness 0.15)
				)
				(justify left bottom)
				(hide yes)
			)
		)
		(pin "1"
		)
		(instances
			(project "jetson-agx-thor-baseboard"
				(path ""
					(reference "#PWR0319")
					(unit 1)
				)
			)
		)
	)
	(symbol
		(lib_id "antmicroResistors0402:R_470R_0402")
		(at 328.93 161.29 90)
		(unit 1)
		(exclude_from_sim no)
		(in_bom yes)
		(on_board yes)
		(dnp no)
		(fields_autoplaced yes)
		(property "Reference" "R178"
			(at 331.47 157.48 90)
			(effects
				(font
					(size 1.27 1.27)
				)
				(justify right)
			)
		)
		(property "Value" "R_470R_0402"
			(at 341.63 140.97 0)
			(effects
				(font
					(size 1.27 1.27)
					(thickness 0.15)
				)
				(justify left bottom)
				(hide yes)
			)
		)
		(property "Footprint" "antmicro-footprints:R_0402_1005Metric"
			(at 344.17 140.97 0)
			(effects
				(font
					(size 1.27 1.27)
					(thickness 0.15)
				)
				(justify left bottom)
				(hide yes)
			)
		)
		(property "Datasheet" "https://www.bourns.com/docs/product-datasheets/cr.pdf"
			(at 346.71 140.97 0)
			(effects
				(font
					(size 1.27 1.27)
					(thickness 0.15)
				)
				(justify left bottom)
				(hide yes)
			)
		)
		(property "Description" "SMD Chip Resistor, 470 ohm, ± 1%, 62.5 mW, 0402 [1005 Metric], Thick Film, General Purpose"
			(at 328.93 161.29 0)
			(effects
				(font
					(size 1.27 1.27)
				)
				(hide yes)
			)
		)
		(property "Manufacturer" "Bourns"
			(at 351.79 140.97 0)
			(effects
				(font
					(size 1.27 1.27)
					(thickness 0.15)
				)
				(justify left bottom)
				(hide yes)
			)
		)
		(property "MPN" "CR0402-FX-4700GLF"
			(at 349.25 140.97 0)
			(effects
				(font
					(size 1.27 1.27)
					(thickness 0.15)
				)
				(justify left bottom)
				(hide yes)
			)
		)
		(property "Val" "470R"
			(at 331.47 160.02 90)
			(effects
				(font
					(size 1.27 1.27)
					(thickness 0.15)
				)
				(justify right)
			)
		)
		(property "License" "Apache-2.0"
			(at 354.33 140.97 0)
			(effects
				(font
					(size 1.27 1.27)
					(thickness 0.15)
				)
				(justify left bottom)
				(hide yes)
			)
		)
		(property "Author" "Antmicro"
			(at 356.87 140.97 0)
			(effects
				(font
					(size 1.27 1.27)
					(thickness 0.15)
				)
				(justify left bottom)
				(hide yes)
			)
		)
		(property "Tolerance" "1%"
			(at 339.09 140.97 0)
			(effects
				(font
					(size 1.27 1.27)
				)
				(justify left bottom)
				(hide yes)
			)
		)
		(pin "1"
		)
		(pin "2"
		)
		(instances
			(project "jetson-agx-thor-baseboard"
				(path ""
					(reference "R178")
					(unit 1)
				)
			)
		)
	)
	(symbol
		(lib_id "antmicroLEDIndicationDiscrete:LED_G_0603_LTST-C190GKT")
		(at 246.38 167.64 90)
		(unit 1)
		(exclude_from_sim no)
		(in_bom yes)
		(on_board yes)
		(dnp no)
		(fields_autoplaced yes)
		(property "Reference" "D28"
			(at 242.57 163.83 90)
			(effects
				(font
					(size 1.27 1.27)
				)
				(justify left)
			)
		)
		(property "Value" "LED_G_0603_LTST-C190GKT"
			(at 254 144.78 0)
			(effects
				(font
					(size 1.27 1.27)
					(thickness 0.15)
				)
				(justify left bottom)
				(hide yes)
			)
		)
		(property "Footprint" "antmicro-footprints:LED_0603_1608Metric_G"
			(at 256.54 144.78 0)
			(effects
				(font
					(size 1.27 1.27)
					(thickness 0.15)
				)
				(justify left bottom)
				(hide yes)
			)
		)
		(property "Datasheet" "https://media.digikey.com/pdf/Data%20Sheets/Lite-On%20PDFs/LTST-C190GKT.pdf"
			(at 259.08 144.78 0)
			(effects
				(font
					(size 1.27 1.27)
					(thickness 0.15)
				)
				(justify left bottom)
				(hide yes)
			)
		)
		(property "Description" "LED, Green, SMD, 0603, 20 mA, 2.1 V, 569 nm"
			(at 246.38 167.64 0)
			(effects
				(font
					(size 1.27 1.27)
				)
				(hide yes)
			)
		)
		(property "MPN" "LTST-C190GKT"
			(at 261.62 144.78 0)
			(effects
				(font
					(size 1.27 1.27)
					(thickness 0.15)
				)
				(justify left bottom)
				(hide yes)
			)
		)
		(property "Manufacturer" "Lite-On"
			(at 264.16 144.78 0)
			(effects
				(font
					(size 1.27 1.27)
					(thickness 0.15)
				)
				(justify left bottom)
				(hide yes)
			)
		)
		(property "Author" "Antmicro"
			(at 266.7 144.78 0)
			(effects
				(font
					(size 1.27 1.27)
					(thickness 0.15)
				)
				(justify left bottom)
				(hide yes)
			)
		)
		(property "License" "Apache-2.0"
			(at 269.24 144.78 0)
			(effects
				(font
					(size 1.27 1.27)
					(thickness 0.15)
				)
				(justify left bottom)
				(hide yes)
			)
		)
		(property "Color" "Green"
			(at 242.57 166.37 90)
			(effects
				(font
					(size 1.27 1.27)
				)
				(justify left)
			)
		)
		(pin "1"
		)
		(pin "2"
		)
		(instances
			(project "jetson-agx-thor-baseboard"
				(path ""
					(reference "D28")
					(unit 1)
				)
			)
		)
	)
	(symbol
		(lib_id "antmicroResistors0402:R_0R_0402")
		(at 276.86 129.54 0)
		(mirror y)
		(unit 1)
		(exclude_from_sim no)
		(in_bom yes)
		(on_board yes)
		(dnp no)
		(property "Reference" "R181"
			(at 269.494 128.524 0)
			(effects
				(font
					(size 1.27 1.27)
					(thickness 0.15)
				)
			)
		)
		(property "Value" "R_0R_0402"
			(at 256.54 142.24 0)
			(effects
				(font
					(size 1.27 1.27)
					(thickness 0.15)
				)
				(justify left bottom)
				(hide yes)
			)
		)
		(property "Footprint" "antmicro-footprints:R_0402_1005Metric"
			(at 256.54 144.78 0)
			(effects
				(font
					(size 1.27 1.27)
					(thickness 0.15)
				)
				(justify left bottom)
				(hide yes)
			)
		)
		(property "Datasheet" "https://industrial.panasonic.com/cdbs/www-data/pdf/RDA0000/AOA0000C301.pdf"
			(at 256.54 147.32 0)
			(effects
				(font
					(size 1.27 1.27)
					(thickness 0.15)
				)
				(justify left bottom)
				(hide yes)
			)
		)
		(property "Description" "SMD Chip Resistor, Jumper, 0 ohm, 100 mW, 0402 [1005 Metric], Thick Film, General Purpose"
			(at 256.54 162.56 0)
			(effects
				(font
					(size 1.27 1.27)
				)
				(justify left bottom)
				(hide yes)
			)
		)
		(property "MPN" "ERJ2GE0R00X"
			(at 256.54 149.86 0)
			(effects
				(font
					(size 1.27 1.27)
					(thickness 0.15)
				)
				(justify left bottom)
				(hide yes)
			)
		)
		(property "Manufacturer" "Panasonic"
			(at 256.54 152.4 0)
			(effects
				(font
					(size 1.27 1.27)
					(thickness 0.15)
				)
				(justify left bottom)
				(hide yes)
			)
		)
		(property "License" "Apache-2.0"
			(at 256.54 154.94 0)
			(effects
				(font
					(size 1.27 1.27)
					(thickness 0.15)
				)
				(justify left bottom)
				(hide yes)
			)
		)
		(property "Author" "Antmicro"
			(at 256.54 157.48 0)
			(effects
				(font
					(size 1.27 1.27)
					(thickness 0.15)
				)
				(justify left bottom)
				(hide yes)
			)
		)
		(property "Val" "0R"
			(at 277.622 128.524 0)
			(effects
				(font
					(size 1.27 1.27)
					(thickness 0.15)
				)
			)
		)
		(property "Tolerance" "~"
			(at 256.54 139.7 0)
			(effects
				(font
					(size 1.27 1.27)
				)
				(justify left bottom)
				(hide yes)
			)
		)
		(property "Current" "1A"
			(at 256.54 160.02 0)
			(effects
				(font
					(size 1.27 1.27)
					(thickness 0.15)
				)
				(justify left bottom)
				(hide yes)
			)
		)
		(pin "2"
		)
		(pin "1"
		)
		(instances
			(project "jetson-agx-thor-baseboard"
				(path ""
					(reference "R181")
					(unit 1)
				)
			)
		)
	)
	(symbol
		(lib_id "antmicroResistors0402:R_10k_0402")
		(at 201.93 208.28 90)
		(unit 1)
		(exclude_from_sim no)
		(in_bom no)
		(on_board yes)
		(dnp yes)
		(property "Reference" "R174"
			(at 203.2 204.47 90)
			(effects
				(font
					(size 1.27 1.27)
				)
				(justify right)
			)
		)
		(property "Value" "R_10k_0402"
			(at 214.63 187.96 0)
			(effects
				(font
					(size 1.27 1.27)
					(thickness 0.15)
				)
				(justify left bottom)
				(hide yes)
			)
		)
		(property "Footprint" "antmicro-footprints:R_0402_1005Metric"
			(at 217.17 187.96 0)
			(effects
				(font
					(size 1.27 1.27)
					(thickness 0.15)
				)
				(justify left bottom)
				(hide yes)
			)
		)
		(property "Datasheet" "https://www.bourns.com/docs/product-datasheets/cr.pdf"
			(at 219.71 187.96 0)
			(effects
				(font
					(size 1.27 1.27)
					(thickness 0.15)
				)
				(justify left bottom)
				(hide yes)
			)
		)
		(property "Description" "SMD Chip Resistor, 10 kohm, ± 1%, 62.5 mW, 0402 [1005 Metric], Thick Film, General Purpose"
			(at 201.93 208.28 0)
			(effects
				(font
					(size 1.27 1.27)
				)
				(hide yes)
			)
		)
		(property "Manufacturer" "Bourns"
			(at 224.79 187.96 0)
			(effects
				(font
					(size 1.27 1.27)
					(thickness 0.15)
				)
				(justify left bottom)
				(hide yes)
			)
		)
		(property "MPN" "CR0402-FX-1002GLF"
			(at 222.25 187.96 0)
			(effects
				(font
					(size 1.27 1.27)
					(thickness 0.15)
				)
				(justify left bottom)
				(hide yes)
			)
		)
		(property "Val" "10k"
			(at 203.2 207.01 90)
			(effects
				(font
					(size 1.27 1.27)
					(thickness 0.15)
				)
				(justify right)
			)
		)
		(property "License" "Apache-2.0"
			(at 227.33 187.96 0)
			(effects
				(font
					(size 1.27 1.27)
					(thickness 0.15)
				)
				(justify left bottom)
				(hide yes)
			)
		)
		(property "Author" "Antmicro"
			(at 229.87 187.96 0)
			(effects
				(font
					(size 1.27 1.27)
					(thickness 0.15)
				)
				(justify left bottom)
				(hide yes)
			)
		)
		(property "Tolerance" "1%"
			(at 212.09 187.96 0)
			(effects
				(font
					(size 1.27 1.27)
				)
				(justify left bottom)
				(hide yes)
			)
		)
		(pin "1"
		)
		(pin "2"
		)
		(instances
			(project "jetson-agx-thor-baseboard"
				(path ""
					(reference "R174")
					(unit 1)
				)
			)
		)
	)
	(symbol
		(lib_id "antmicropower:+5V")
		(at 212.09 200.66 0)
		(unit 1)
		(exclude_from_sim no)
		(in_bom yes)
		(on_board yes)
		(dnp no)
		(property "Reference" "#PWR0310"
			(at 212.09 204.47 0)
			(effects
				(font
					(size 1.27 1.27)
				)
				(justify left bottom)
				(hide yes)
			)
		)
		(property "Value" "+5V"
			(at 209.55 196.85 0)
			(effects
				(font
					(size 1.27 1.27)
					(thickness 0.15)
				)
				(justify left)
			)
		)
		(property "Footprint" ""
			(at 227.33 208.28 0)
			(effects
				(font
					(size 1.27 1.27)
					(thickness 0.15)
				)
				(justify left bottom)
				(hide yes)
			)
		)
		(property "Datasheet" ""
			(at 227.33 210.82 0)
			(effects
				(font
					(size 1.27 1.27)
					(thickness 0.15)
				)
				(justify left bottom)
				(hide yes)
			)
		)
		(property "Description" ""
			(at 212.09 200.66 0)
			(effects
				(font
					(size 1.27 1.27)
				)
				(hide yes)
			)
		)
		(property "Author" "Antmicro"
			(at 227.33 208.28 0)
			(effects
				(font
					(size 1.27 1.27)
					(thickness 0.15)
				)
				(justify left bottom)
				(hide yes)
			)
		)
		(property "License" "Apache-2.0"
			(at 227.33 210.82 0)
			(effects
				(font
					(size 1.27 1.27)
					(thickness 0.15)
				)
				(justify left bottom)
				(hide yes)
			)
		)
		(pin "1"
		)
		(instances
			(project "jetson-agx-thor-baseboard"
				(path ""
					(reference "#PWR0310")
					(unit 1)
				)
			)
		)
	)
	(symbol
		(lib_id "antmicroPMICPowerDistributionSwitchesLoadDrivers:AP22615A_TSOT26")
		(at 228.6 243.84 0)
		(unit 1)
		(exclude_from_sim no)
		(in_bom yes)
		(on_board yes)
		(dnp no)
		(property "Reference" "U47"
			(at 236.22 237.49 0)
			(effects
				(font
					(size 1.27 1.27)
				)
			)
		)
		(property "Value" "AP22615A_TSOT26"
			(at 259.08 248.92 0)
			(effects
				(font
					(size 1.27 1.27)
					(thickness 0.15)
				)
				(justify left bottom)
				(hide yes)
			)
		)
		(property "Footprint" "antmicro-footprints:TSOT23-6"
			(at 259.08 251.46 0)
			(effects
				(font
					(size 1.27 1.27)
					(thickness 0.15)
				)
				(justify left bottom)
				(hide yes)
			)
		)
		(property "Datasheet" "https://www.mouser.com/datasheet/2/115/DIOD_S_A0008958405_1-2543193.pdf"
			(at 259.08 254 0)
			(effects
				(font
					(size 1.27 1.27)
					(thickness 0.15)
				)
				(justify left bottom)
				(hide yes)
			)
		)
		(property "Description" "Power Load Distribution Switch, High Side, Active High, 1 Output, 5.5 V, 3.6 A, 0.04 ohm, TSOT-26-6"
			(at 228.6 243.84 0)
			(effects
				(font
					(size 1.27 1.27)
				)
				(hide yes)
			)
		)
		(property "MPN" "AP22615AWU-7"
			(at 236.22 240.03 0)
			(effects
				(font
					(size 1.27 1.27)
					(thickness 0.15)
				)
			)
		)
		(property "Manufacturer" "Diodes Incorporated"
			(at 259.08 259.08 0)
			(effects
				(font
					(size 1.27 1.27)
					(thickness 0.15)
				)
				(justify left bottom)
				(hide yes)
			)
		)
		(property "Author" "Antmicro"
			(at 259.08 261.62 0)
			(effects
				(font
					(size 1.27 1.27)
					(thickness 0.15)
				)
				(justify left bottom)
				(hide yes)
			)
		)
		(property "License" "Apache-2.0"
			(at 259.08 264.16 0)
			(effects
				(font
					(size 1.27 1.27)
					(thickness 0.15)
				)
				(justify left bottom)
				(hide yes)
			)
		)
		(pin "1"
		)
		(pin "2"
		)
		(pin "3"
		)
		(pin "4"
		)
		(pin "5"
		)
		(pin "6"
		)
		(instances
			(project "jetson-agx-thor-baseboard"
				(path ""
					(reference "U47")
					(unit 1)
				)
			)
		)
	)
	(symbol
		(lib_id "antmicropower:GND")
		(at 334.01 204.47 0)
		(unit 1)
		(exclude_from_sim no)
		(in_bom yes)
		(on_board yes)
		(dnp no)
		(property "Reference" "#PWR0327"
			(at 334.01 210.82 0)
			(effects
				(font
					(size 1.27 1.27)
				)
				(justify left bottom)
				(hide yes)
			)
		)
		(property "Value" "GND"
			(at 334.01 208.28 0)
			(effects
				(font
					(size 1.27 1.27)
					(thickness 0.15)
				)
			)
		)
		(property "Footprint" ""
			(at 342.9 212.09 0)
			(effects
				(font
					(size 1.27 1.27)
					(thickness 0.15)
				)
				(justify left bottom)
				(hide yes)
			)
		)
		(property "Datasheet" ""
			(at 342.9 217.17 0)
			(effects
				(font
					(size 1.27 1.27)
					(thickness 0.15)
				)
				(justify left bottom)
				(hide yes)
			)
		)
		(property "Description" ""
			(at 334.01 204.47 0)
			(effects
				(font
					(size 1.27 1.27)
				)
				(hide yes)
			)
		)
		(property "Author" "Antmicro"
			(at 342.9 212.09 0)
			(effects
				(font
					(size 1.27 1.27)
					(thickness 0.15)
				)
				(justify left bottom)
				(hide yes)
			)
		)
		(property "License" "Apache-2.0"
			(at 342.9 214.63 0)
			(effects
				(font
					(size 1.27 1.27)
					(thickness 0.15)
				)
				(justify left bottom)
				(hide yes)
			)
		)
		(pin "1"
		)
		(instances
			(project "jetson-agx-thor-baseboard"
				(path ""
					(reference "#PWR0327")
					(unit 1)
				)
			)
		)
	)
	(symbol
		(lib_id "antmicroResistors0402:R_100k_0402")
		(at 207.01 255.27 90)
		(unit 1)
		(exclude_from_sim no)
		(in_bom yes)
		(on_board yes)
		(dnp no)
		(property "Reference" "R175"
			(at 208.28 251.46 90)
			(effects
				(font
					(size 1.27 1.27)
				)
				(justify right)
			)
		)
		(property "Value" "R_100k_0402"
			(at 219.71 234.95 0)
			(effects
				(font
					(size 1.27 1.27)
					(thickness 0.15)
				)
				(justify left bottom)
				(hide yes)
			)
		)
		(property "Footprint" "antmicro-footprints:R_0402_1005Metric"
			(at 222.25 234.95 0)
			(effects
				(font
					(size 1.27 1.27)
					(thickness 0.15)
				)
				(justify left bottom)
				(hide yes)
			)
		)
		(property "Datasheet" "https://www.bourns.com/docs/product-datasheets/cr.pdf"
			(at 224.79 234.95 0)
			(effects
				(font
					(size 1.27 1.27)
					(thickness 0.15)
				)
				(justify left bottom)
				(hide yes)
			)
		)
		(property "Description" "SMD Chip Resistor, 100 kohm, ± 1%, 62.5 mW, 0402 [1005 Metric], Thick Film, General Purpose"
			(at 207.01 255.27 0)
			(effects
				(font
					(size 1.27 1.27)
				)
				(hide yes)
			)
		)
		(property "Manufacturer" "Bourns"
			(at 229.87 234.95 0)
			(effects
				(font
					(size 1.27 1.27)
					(thickness 0.15)
				)
				(justify left bottom)
				(hide yes)
			)
		)
		(property "MPN" "CR0402-FX-1003GLF"
			(at 227.33 234.95 0)
			(effects
				(font
					(size 1.27 1.27)
					(thickness 0.15)
				)
				(justify left bottom)
				(hide yes)
			)
		)
		(property "Val" "100k"
			(at 208.28 254 90)
			(effects
				(font
					(size 1.27 1.27)
					(thickness 0.15)
				)
				(justify right)
			)
		)
		(property "License" "Apache-2.0"
			(at 232.41 234.95 0)
			(effects
				(font
					(size 1.27 1.27)
					(thickness 0.15)
				)
				(justify left bottom)
				(hide yes)
			)
		)
		(property "Author" "Antmicro"
			(at 234.95 234.95 0)
			(effects
				(font
					(size 1.27 1.27)
					(thickness 0.15)
				)
				(justify left bottom)
				(hide yes)
			)
		)
		(property "Tolerance" "1%"
			(at 217.17 234.95 0)
			(effects
				(font
					(size 1.27 1.27)
				)
				(justify left bottom)
				(hide yes)
			)
		)
		(pin "1"
		)
		(pin "2"
		)
		(instances
			(project "jetson-agx-thor-baseboard"
				(path ""
					(reference "R175")
					(unit 1)
				)
			)
		)
	)
	(symbol
		(lib_id "antmicropower:GND")
		(at 135.89 220.98 0)
		(unit 1)
		(exclude_from_sim no)
		(in_bom yes)
		(on_board yes)
		(dnp no)
		(property "Reference" "#PWR0304"
			(at 135.89 227.33 0)
			(effects
				(font
					(size 1.27 1.27)
				)
				(justify left bottom)
				(hide yes)
			)
		)
		(property "Value" "GND"
			(at 135.89 224.79 0)
			(effects
				(font
					(size 1.27 1.27)
					(thickness 0.15)
				)
			)
		)
		(property "Footprint" ""
			(at 144.78 228.6 0)
			(effects
				(font
					(size 1.27 1.27)
					(thickness 0.15)
				)
				(justify left bottom)
				(hide yes)
			)
		)
		(property "Datasheet" ""
			(at 144.78 233.68 0)
			(effects
				(font
					(size 1.27 1.27)
					(thickness 0.15)
				)
				(justify left bottom)
				(hide yes)
			)
		)
		(property "Description" ""
			(at 135.89 220.98 0)
			(effects
				(font
					(size 1.27 1.27)
				)
				(hide yes)
			)
		)
		(property "Author" "Antmicro"
			(at 144.78 228.6 0)
			(effects
				(font
					(size 1.27 1.27)
					(thickness 0.15)
				)
				(justify left bottom)
				(hide yes)
			)
		)
		(property "License" "Apache-2.0"
			(at 144.78 231.14 0)
			(effects
				(font
					(size 1.27 1.27)
					(thickness 0.15)
				)
				(justify left bottom)
				(hide yes)
			)
		)
		(pin "1"
		)
		(instances
			(project "jetson-agx-thor-baseboard"
				(path ""
					(reference "#PWR0304")
					(unit 1)
				)
			)
		)
	)
	(symbol
		(lib_id "antmicropower:+3V3")
		(at 76.2 134.62 0)
		(unit 1)
		(exclude_from_sim no)
		(in_bom yes)
		(on_board yes)
		(dnp no)
		(property "Reference" "#PWR0287"
			(at 76.2 138.43 0)
			(effects
				(font
					(size 1.27 1.27)
				)
				(justify left bottom)
				(hide yes)
			)
		)
		(property "Value" "+3V3"
			(at 75.565 130.81 0)
			(effects
				(font
					(size 1.27 1.27)
					(thickness 0.15)
				)
			)
		)
		(property "Footprint" ""
			(at 91.44 142.24 0)
			(effects
				(font
					(size 1.27 1.27)
					(thickness 0.15)
				)
				(justify left bottom)
				(hide yes)
			)
		)
		(property "Datasheet" ""
			(at 91.44 144.78 0)
			(effects
				(font
					(size 1.27 1.27)
					(thickness 0.15)
				)
				(justify left bottom)
				(hide yes)
			)
		)
		(property "Description" ""
			(at 76.2 134.62 0)
			(effects
				(font
					(size 1.27 1.27)
				)
				(hide yes)
			)
		)
		(property "Author" "Antmicro"
			(at 91.44 137.16 0)
			(effects
				(font
					(size 1.27 1.27)
					(thickness 0.15)
				)
				(justify left bottom)
				(hide yes)
			)
		)
		(property "License" "Apache-2.0"
			(at 91.44 139.7 0)
			(effects
				(font
					(size 1.27 1.27)
					(thickness 0.15)
				)
				(justify left bottom)
				(hide yes)
			)
		)
		(pin "1"
		)
		(instances
			(project "jetson-agx-thor-baseboard"
				(path ""
					(reference "#PWR0287")
					(unit 1)
				)
			)
		)
	)
	(symbol
		(lib_id "antmicropower:GND")
		(at 284.48 163.83 0)
		(unit 1)
		(exclude_from_sim no)
		(in_bom yes)
		(on_board yes)
		(dnp no)
		(property "Reference" "#PWR0332"
			(at 284.48 170.18 0)
			(effects
				(font
					(size 1.27 1.27)
				)
				(justify left bottom)
				(hide yes)
			)
		)
		(property "Value" "GND"
			(at 284.48 167.64 0)
			(effects
				(font
					(size 1.27 1.27)
					(thickness 0.15)
				)
			)
		)
		(property "Footprint" ""
			(at 293.37 171.45 0)
			(effects
				(font
					(size 1.27 1.27)
					(thickness 0.15)
				)
				(justify left bottom)
				(hide yes)
			)
		)
		(property "Datasheet" ""
			(at 293.37 176.53 0)
			(effects
				(font
					(size 1.27 1.27)
					(thickness 0.15)
				)
				(justify left bottom)
				(hide yes)
			)
		)
		(property "Description" ""
			(at 284.48 163.83 0)
			(effects
				(font
					(size 1.27 1.27)
				)
				(hide yes)
			)
		)
		(property "Author" "Antmicro"
			(at 293.37 171.45 0)
			(effects
				(font
					(size 1.27 1.27)
					(thickness 0.15)
				)
				(justify left bottom)
				(hide yes)
			)
		)
		(property "License" "Apache-2.0"
			(at 293.37 173.99 0)
			(effects
				(font
					(size 1.27 1.27)
					(thickness 0.15)
				)
				(justify left bottom)
				(hide yes)
			)
		)
		(pin "1"
		)
		(instances
			(project "jetson-agx-thor-baseboard"
				(path ""
					(reference "#PWR0332")
					(unit 1)
				)
			)
		)
	)
	(symbol
		(lib_id "antmicroTestPoints:TP_0.75mm_SMD")
		(at 147.32 101.6 0)
		(unit 1)
		(exclude_from_sim no)
		(in_bom no)
		(on_board yes)
		(dnp no)
		(property "Reference" "TP26"
			(at 151.13 101.5999 0)
			(effects
				(font
					(size 1.27 1.27)
				)
				(justify left)
			)
		)
		(property "Value" "TP_0.75mm_SMD"
			(at 157.48 105.41 0)
			(effects
				(font
					(size 1.27 1.27)
					(thickness 0.15)
				)
				(justify left bottom)
				(hide yes)
			)
		)
		(property "Footprint" "antmicro-footprints:TP_SMD_0.75mm"
			(at 157.48 107.95 0)
			(effects
				(font
					(size 1.27 1.27)
					(thickness 0.15)
				)
				(justify left bottom)
				(hide yes)
			)
		)
		(property "Datasheet" ""
			(at 165.1 114.3 0)
			(effects
				(font
					(size 1.27 1.27)
					(thickness 0.15)
				)
				(justify left bottom)
				(hide yes)
			)
		)
		(property "Description" "SMT test point"
			(at 147.32 101.6 0)
			(effects
				(font
					(size 1.27 1.27)
				)
				(hide yes)
			)
		)
		(property "MPN" ""
			(at 158.115 113.03 0)
			(effects
				(font
					(size 1.27 1.27)
					(thickness 0.15)
				)
				(justify left bottom)
				(hide yes)
			)
		)
		(property "Manufacturer" ""
			(at 158.115 107.95 0)
			(effects
				(font
					(size 1.27 1.27)
					(thickness 0.15)
				)
				(justify left bottom)
				(hide yes)
			)
		)
		(property "Author" "Antmicro"
			(at 157.48 110.49 0)
			(effects
				(font
					(size 1.27 1.27)
					(thickness 0.15)
				)
				(justify left bottom)
				(hide yes)
			)
		)
		(property "License" "Apache-2.0"
			(at 157.48 113.03 0)
			(effects
				(font
					(size 1.27 1.27)
					(thickness 0.15)
				)
				(justify left bottom)
				(hide yes)
			)
		)
		(pin "1"
		)
		(instances
			(project "jetson-agx-thor-baseboard"
				(path ""
					(reference "TP26")
					(unit 1)
				)
			)
		)
	)
	(symbol
		(lib_id "antmicroResistors0402:R_10k_0402")
		(at 93.98 82.55 270)
		(unit 1)
		(exclude_from_sim no)
		(in_bom yes)
		(on_board yes)
		(dnp no)
		(property "Reference" "R167"
			(at 95.25 83.82 90)
			(effects
				(font
					(size 1.27 1.27)
				)
				(justify left)
			)
		)
		(property "Value" "R_10k_0402"
			(at 81.28 102.87 0)
			(effects
				(font
					(size 1.27 1.27)
					(thickness 0.15)
				)
				(justify left bottom)
				(hide yes)
			)
		)
		(property "Footprint" "antmicro-footprints:R_0402_1005Metric"
			(at 78.74 102.87 0)
			(effects
				(font
					(size 1.27 1.27)
					(thickness 0.15)
				)
				(justify left bottom)
				(hide yes)
			)
		)
		(property "Datasheet" "https://www.bourns.com/docs/product-datasheets/cr.pdf"
			(at 76.2 102.87 0)
			(effects
				(font
					(size 1.27 1.27)
					(thickness 0.15)
				)
				(justify left bottom)
				(hide yes)
			)
		)
		(property "Description" "SMD Chip Resistor, 10 kohm, ± 1%, 62.5 mW, 0402 [1005 Metric], Thick Film, General Purpose"
			(at 93.98 82.55 0)
			(effects
				(font
					(size 1.27 1.27)
				)
				(hide yes)
			)
		)
		(property "Manufacturer" "Bourns"
			(at 71.12 102.87 0)
			(effects
				(font
					(size 1.27 1.27)
					(thickness 0.15)
				)
				(justify left bottom)
				(hide yes)
			)
		)
		(property "MPN" "CR0402-FX-1002GLF"
			(at 73.66 102.87 0)
			(effects
				(font
					(size 1.27 1.27)
					(thickness 0.15)
				)
				(justify left bottom)
				(hide yes)
			)
		)
		(property "Val" "10k"
			(at 95.25 86.36 90)
			(effects
				(font
					(size 1.27 1.27)
					(thickness 0.15)
				)
				(justify left)
			)
		)
		(property "License" "Apache-2.0"
			(at 68.58 102.87 0)
			(effects
				(font
					(size 1.27 1.27)
					(thickness 0.15)
				)
				(justify left bottom)
				(hide yes)
			)
		)
		(property "Author" "Antmicro"
			(at 66.04 102.87 0)
			(effects
				(font
					(size 1.27 1.27)
					(thickness 0.15)
				)
				(justify left bottom)
				(hide yes)
			)
		)
		(property "Tolerance" "1%"
			(at 83.82 102.87 0)
			(effects
				(font
					(size 1.27 1.27)
				)
				(justify left bottom)
				(hide yes)
			)
		)
		(pin "1"
		)
		(pin "2"
		)
		(instances
			(project "jetson-agx-thor-baseboard"
				(path ""
					(reference "R167")
					(unit 1)
				)
			)
		)
	)
	(symbol
		(lib_id "antmicroResistors0402:R_0R_0402")
		(at 90.17 66.04 180)
		(unit 1)
		(exclude_from_sim no)
		(in_bom yes)
		(on_board yes)
		(dnp no)
		(property "Reference" "R162"
			(at 90.17 65.405 0)
			(effects
				(font
					(size 1.27 1.27)
				)
				(justify right top)
			)
		)
		(property "Value" "R_0R_0402"
			(at 69.85 53.34 0)
			(effects
				(font
					(size 1.27 1.27)
					(thickness 0.15)
				)
				(justify left bottom)
				(hide yes)
			)
		)
		(property "Footprint" "antmicro-footprints:R_0402_1005Metric"
			(at 69.85 50.8 0)
			(effects
				(font
					(size 1.27 1.27)
					(thickness 0.15)
				)
				(justify left bottom)
				(hide yes)
			)
		)
		(property "Datasheet" "https://industrial.panasonic.com/cdbs/www-data/pdf/RDA0000/AOA0000C301.pdf"
			(at 69.85 48.26 0)
			(effects
				(font
					(size 1.27 1.27)
					(thickness 0.15)
				)
				(justify left bottom)
				(hide yes)
			)
		)
		(property "Description" "SMD Chip Resistor, Jumper, 0 ohm, 100 mW, 0402 [1005 Metric], Thick Film, General Purpose"
			(at 90.17 66.04 0)
			(effects
				(font
					(size 1.27 1.27)
				)
				(hide yes)
			)
		)
		(property "Manufacturer" "Panasonic"
			(at 69.85 43.18 0)
			(effects
				(font
					(size 1.27 1.27)
					(thickness 0.15)
				)
				(justify left bottom)
				(hide yes)
			)
		)
		(property "MPN" "ERJ2GE0R00X"
			(at 69.85 45.72 0)
			(effects
				(font
					(size 1.27 1.27)
					(thickness 0.15)
				)
				(justify left bottom)
				(hide yes)
			)
		)
		(property "Val" "0R"
			(at 82.55 65.405 0)
			(effects
				(font
					(size 1.27 1.27)
					(thickness 0.15)
				)
				(justify right top)
			)
		)
		(property "License" "Apache-2.0"
			(at 69.85 40.64 0)
			(effects
				(font
					(size 1.27 1.27)
					(thickness 0.15)
				)
				(justify left bottom)
				(hide yes)
			)
		)
		(property "Author" "Antmicro"
			(at 69.85 38.1 0)
			(effects
				(font
					(size 1.27 1.27)
					(thickness 0.15)
				)
				(justify left bottom)
				(hide yes)
			)
		)
		(property "Tolerance" "~"
			(at 69.85 55.88 0)
			(effects
				(font
					(size 1.27 1.27)
				)
				(justify left bottom)
				(hide yes)
			)
		)
		(property "Current" "1A"
			(at 69.85 35.56 0)
			(effects
				(font
					(size 1.27 1.27)
					(thickness 0.15)
				)
				(justify left bottom)
				(hide yes)
			)
		)
		(pin "1"
		)
		(pin "2"
		)
		(instances
			(project "jetson-agx-thor-baseboard"
				(path ""
					(reference "R162")
					(unit 1)
				)
			)
		)
	)
	(symbol
		(lib_id "antmicropower:GND")
		(at 328.93 168.91 0)
		(unit 1)
		(exclude_from_sim no)
		(in_bom yes)
		(on_board yes)
		(dnp no)
		(property "Reference" "#PWR0318"
			(at 328.93 175.26 0)
			(effects
				(font
					(size 1.27 1.27)
				)
				(justify left bottom)
				(hide yes)
			)
		)
		(property "Value" "GND"
			(at 328.93 172.72 0)
			(effects
				(font
					(size 1.27 1.27)
					(thickness 0.15)
				)
			)
		)
		(property "Footprint" ""
			(at 337.82 176.53 0)
			(effects
				(font
					(size 1.27 1.27)
					(thickness 0.15)
				)
				(justify left bottom)
				(hide yes)
			)
		)
		(property "Datasheet" ""
			(at 337.82 181.61 0)
			(effects
				(font
					(size 1.27 1.27)
					(thickness 0.15)
				)
				(justify left bottom)
				(hide yes)
			)
		)
		(property "Description" ""
			(at 328.93 168.91 0)
			(effects
				(font
					(size 1.27 1.27)
				)
				(hide yes)
			)
		)
		(property "Author" "Antmicro"
			(at 337.82 176.53 0)
			(effects
				(font
					(size 1.27 1.27)
					(thickness 0.15)
				)
				(justify left bottom)
				(hide yes)
			)
		)
		(property "License" "Apache-2.0"
			(at 337.82 179.07 0)
			(effects
				(font
					(size 1.27 1.27)
					(thickness 0.15)
				)
				(justify left bottom)
				(hide yes)
			)
		)
		(pin "1"
		)
		(instances
			(project "jetson-agx-thor-baseboard"
				(path ""
					(reference "#PWR0318")
					(unit 1)
				)
			)
		)
	)
	(symbol
		(lib_id "antmicropower:+5V")
		(at 102.87 200.66 0)
		(unit 1)
		(exclude_from_sim no)
		(in_bom yes)
		(on_board yes)
		(dnp no)
		(property "Reference" "#PWR0296"
			(at 102.87 204.47 0)
			(effects
				(font
					(size 1.27 1.27)
				)
				(justify left bottom)
				(hide yes)
			)
		)
		(property "Value" "+5V"
			(at 100.33 196.85 0)
			(effects
				(font
					(size 1.27 1.27)
					(thickness 0.15)
				)
				(justify left)
			)
		)
		(property "Footprint" ""
			(at 118.11 208.28 0)
			(effects
				(font
					(size 1.27 1.27)
					(thickness 0.15)
				)
				(justify left bottom)
				(hide yes)
			)
		)
		(property "Datasheet" ""
			(at 118.11 210.82 0)
			(effects
				(font
					(size 1.27 1.27)
					(thickness 0.15)
				)
				(justify left bottom)
				(hide yes)
			)
		)
		(property "Description" ""
			(at 102.87 200.66 0)
			(effects
				(font
					(size 1.27 1.27)
				)
				(hide yes)
			)
		)
		(property "Author" "Antmicro"
			(at 118.11 208.28 0)
			(effects
				(font
					(size 1.27 1.27)
					(thickness 0.15)
				)
				(justify left bottom)
				(hide yes)
			)
		)
		(property "License" "Apache-2.0"
			(at 118.11 210.82 0)
			(effects
				(font
					(size 1.27 1.27)
					(thickness 0.15)
				)
				(justify left bottom)
				(hide yes)
			)
		)
		(pin "1"
		)
		(instances
			(project "jetson-agx-thor-baseboard"
				(path ""
					(reference "#PWR0296")
					(unit 1)
				)
			)
		)
	)
	(symbol
		(lib_id "antmicropower:GND")
		(at 85.09 106.68 0)
		(unit 1)
		(exclude_from_sim no)
		(in_bom yes)
		(on_board yes)
		(dnp no)
		(property "Reference" "#PWR0289"
			(at 85.09 113.03 0)
			(effects
				(font
					(size 1.27 1.27)
				)
				(justify left bottom)
				(hide yes)
			)
		)
		(property "Value" "GND"
			(at 85.09 110.49 0)
			(effects
				(font
					(size 1.27 1.27)
					(thickness 0.15)
				)
			)
		)
		(property "Footprint" ""
			(at 93.98 114.3 0)
			(effects
				(font
					(size 1.27 1.27)
					(thickness 0.15)
				)
				(justify left bottom)
				(hide yes)
			)
		)
		(property "Datasheet" ""
			(at 93.98 119.38 0)
			(effects
				(font
					(size 1.27 1.27)
					(thickness 0.15)
				)
				(justify left bottom)
				(hide yes)
			)
		)
		(property "Description" ""
			(at 85.09 106.68 0)
			(effects
				(font
					(size 1.27 1.27)
				)
				(hide yes)
			)
		)
		(property "Author" "Antmicro"
			(at 93.98 114.3 0)
			(effects
				(font
					(size 1.27 1.27)
					(thickness 0.15)
				)
				(justify left bottom)
				(hide yes)
			)
		)
		(property "License" "Apache-2.0"
			(at 93.98 116.84 0)
			(effects
				(font
					(size 1.27 1.27)
					(thickness 0.15)
				)
				(justify left bottom)
				(hide yes)
			)
		)
		(pin "1"
		)
		(instances
			(project "jetson-agx-thor-baseboard"
				(path ""
					(reference "#PWR0289")
					(unit 1)
				)
			)
		)
	)
	(symbol
		(lib_id "antmicropower:+3V3")
		(at 201.93 200.66 0)
		(unit 1)
		(exclude_from_sim no)
		(in_bom yes)
		(on_board yes)
		(dnp no)
		(property "Reference" "#PWR0308"
			(at 201.93 204.47 0)
			(effects
				(font
					(size 1.27 1.27)
				)
				(justify left bottom)
				(hide yes)
			)
		)
		(property "Value" "+3V3"
			(at 198.755 196.85 0)
			(effects
				(font
					(size 1.27 1.27)
					(thickness 0.15)
				)
				(justify left)
			)
		)
		(property "Footprint" ""
			(at 217.17 208.28 0)
			(effects
				(font
					(size 1.27 1.27)
					(thickness 0.15)
				)
				(justify left bottom)
				(hide yes)
			)
		)
		(property "Datasheet" ""
			(at 217.17 210.82 0)
			(effects
				(font
					(size 1.27 1.27)
					(thickness 0.15)
				)
				(justify left bottom)
				(hide yes)
			)
		)
		(property "Description" ""
			(at 201.93 200.66 0)
			(effects
				(font
					(size 1.27 1.27)
				)
				(hide yes)
			)
		)
		(property "Author" "Antmicro"
			(at 217.17 203.2 0)
			(effects
				(font
					(size 1.27 1.27)
					(thickness 0.15)
				)
				(justify left bottom)
				(hide yes)
			)
		)
		(property "License" "Apache-2.0"
			(at 217.17 205.74 0)
			(effects
				(font
					(size 1.27 1.27)
					(thickness 0.15)
				)
				(justify left bottom)
				(hide yes)
			)
		)
		(pin "1"
		)
		(instances
			(project "jetson-agx-thor-baseboard"
				(path ""
					(reference "#PWR0308")
					(unit 1)
				)
			)
		)
	)
	(symbol
		(lib_id "antmicroLEDIndicationDiscrete:LED_G_0603_LTST-C190GKT")
		(at 323.85 167.64 90)
		(unit 1)
		(exclude_from_sim no)
		(in_bom yes)
		(on_board yes)
		(dnp no)
		(fields_autoplaced yes)
		(property "Reference" "D26"
			(at 320.04 163.83 90)
			(effects
				(font
					(size 1.27 1.27)
				)
				(justify left)
			)
		)
		(property "Value" "LED_G_0603_LTST-C190GKT"
			(at 331.47 144.78 0)
			(effects
				(font
					(size 1.27 1.27)
					(thickness 0.15)
				)
				(justify left bottom)
				(hide yes)
			)
		)
		(property "Footprint" "antmicro-footprints:LED_0603_1608Metric_G"
			(at 334.01 144.78 0)
			(effects
				(font
					(size 1.27 1.27)
					(thickness 0.15)
				)
				(justify left bottom)
				(hide yes)
			)
		)
		(property "Datasheet" "https://media.digikey.com/pdf/Data%20Sheets/Lite-On%20PDFs/LTST-C190GKT.pdf"
			(at 336.55 144.78 0)
			(effects
				(font
					(size 1.27 1.27)
					(thickness 0.15)
				)
				(justify left bottom)
				(hide yes)
			)
		)
		(property "Description" "LED, Green, SMD, 0603, 20 mA, 2.1 V, 569 nm"
			(at 323.85 167.64 0)
			(effects
				(font
					(size 1.27 1.27)
				)
				(hide yes)
			)
		)
		(property "MPN" "LTST-C190GKT"
			(at 339.09 144.78 0)
			(effects
				(font
					(size 1.27 1.27)
					(thickness 0.15)
				)
				(justify left bottom)
				(hide yes)
			)
		)
		(property "Manufacturer" "Lite-On"
			(at 341.63 144.78 0)
			(effects
				(font
					(size 1.27 1.27)
					(thickness 0.15)
				)
				(justify left bottom)
				(hide yes)
			)
		)
		(property "Author" "Antmicro"
			(at 344.17 144.78 0)
			(effects
				(font
					(size 1.27 1.27)
					(thickness 0.15)
				)
				(justify left bottom)
				(hide yes)
			)
		)
		(property "License" "Apache-2.0"
			(at 346.71 144.78 0)
			(effects
				(font
					(size 1.27 1.27)
					(thickness 0.15)
				)
				(justify left bottom)
				(hide yes)
			)
		)
		(property "Color" "Green"
			(at 320.04 166.37 90)
			(effects
				(font
					(size 1.27 1.27)
				)
				(justify left)
			)
		)
		(pin "1"
		)
		(pin "2"
		)
		(instances
			(project "jetson-agx-thor-baseboard"
				(path ""
					(reference "D26")
					(unit 1)
				)
			)
		)
	)
	(symbol
		(lib_id "antmicroCapacitors0402:C_1u_0402")
		(at 344.17 161.29 90)
		(unit 1)
		(exclude_from_sim no)
		(in_bom yes)
		(on_board yes)
		(dnp no)
		(fields_autoplaced yes)
		(property "Reference" "C160"
			(at 341.63 157.4736 90)
			(effects
				(font
					(size 1.27 1.27)
				)
				(justify left)
			)
		)
		(property "Value" "C_1u_0402"
			(at 354.33 140.97 0)
			(effects
				(font
					(size 1.27 1.27)
					(thickness 0.15)
				)
				(justify left bottom)
				(hide yes)
			)
		)
		(property "Footprint" "antmicro-footprints:C_0402_1005Metric"
			(at 356.87 140.97 0)
			(effects
				(font
					(size 1.27 1.27)
					(thickness 0.15)
				)
				(justify left bottom)
				(hide yes)
			)
		)
		(property "Datasheet" "https://product.tdk.com/en/search/capacitor/ceramic/mlcc/info?part_no=C1005X6S1A105K050BC"
			(at 359.41 140.97 0)
			(effects
				(font
					(size 1.27 1.27)
					(thickness 0.15)
				)
				(justify left bottom)
				(hide yes)
			)
		)
		(property "Description" "SMD Multilayer Ceramic Capacitor, 1 µF, 10 V, 0402 [1005 Metric], ± 10%, X6S, C"
			(at 344.17 161.29 0)
			(effects
				(font
					(size 1.27 1.27)
				)
				(hide yes)
			)
		)
		(property "Manufacturer" "TDK"
			(at 364.49 140.97 0)
			(effects
				(font
					(size 1.27 1.27)
					(thickness 0.15)
				)
				(justify left bottom)
				(hide yes)
			)
		)
		(property "MPN" "C1005X6S1A105K050BC"
			(at 361.95 140.97 0)
			(effects
				(font
					(size 1.27 1.27)
					(thickness 0.15)
				)
				(justify left bottom)
				(hide yes)
			)
		)
		(property "Val" "1u"
			(at 341.63 160.0136 90)
			(effects
				(font
					(size 1.27 1.27)
					(thickness 0.15)
				)
				(justify left)
			)
		)
		(property "License" "Apache-2.0"
			(at 367.03 140.97 0)
			(effects
				(font
					(size 1.27 1.27)
					(thickness 0.15)
				)
				(justify left bottom)
				(hide yes)
			)
		)
		(property "Author" "Antmicro"
			(at 369.57 140.97 0)
			(effects
				(font
					(size 1.27 1.27)
					(thickness 0.15)
				)
				(justify left bottom)
				(hide yes)
			)
		)
		(property "Voltage" ""
			(at 372.11 140.97 0)
			(effects
				(font
					(size 1.27 1.27)
				)
				(justify left bottom)
				(hide yes)
			)
		)
		(property "Dielectric" ""
			(at 374.65 140.97 0)
			(effects
				(font
					(size 1.27 1.27)
				)
				(justify left bottom)
				(hide yes)
			)
		)
		(pin "1"
		)
		(pin "2"
		)
		(instances
			(project "jetson-agx-thor-baseboard"
				(path ""
					(reference "C160")
					(unit 1)
				)
			)
		)
	)
	(symbol
		(lib_id "antmicropower:+1V8")
		(at 99.06 48.26 0)
		(unit 1)
		(exclude_from_sim no)
		(in_bom yes)
		(on_board yes)
		(dnp no)
		(property "Reference" "#PWR0294"
			(at 99.06 52.07 0)
			(effects
				(font
					(size 1.27 1.27)
				)
				(justify left bottom)
				(hide yes)
			)
		)
		(property "Value" "+1V8"
			(at 96.52 44.45 0)
			(effects
				(font
					(size 1.27 1.27)
					(thickness 0.15)
				)
				(justify left)
			)
		)
		(property "Footprint" ""
			(at 114.3 55.88 0)
			(effects
				(font
					(size 1.27 1.27)
					(thickness 0.15)
				)
				(justify left bottom)
				(hide yes)
			)
		)
		(property "Datasheet" ""
			(at 114.3 58.42 0)
			(effects
				(font
					(size 1.27 1.27)
					(thickness 0.15)
				)
				(justify left bottom)
				(hide yes)
			)
		)
		(property "Description" ""
			(at 99.06 48.26 0)
			(effects
				(font
					(size 1.27 1.27)
				)
				(hide yes)
			)
		)
		(property "Author" "Antmicro"
			(at 114.3 53.34 0)
			(effects
				(font
					(size 1.27 1.27)
					(thickness 0.15)
				)
				(justify left bottom)
				(hide yes)
			)
		)
		(property "License" "Apache-2.0"
			(at 114.3 55.88 0)
			(effects
				(font
					(size 1.27 1.27)
					(thickness 0.15)
				)
				(justify left bottom)
				(hide yes)
			)
		)
		(pin "1"
		)
		(instances
			(project "jetson-agx-thor-baseboard"
				(path ""
					(reference "#PWR0294")
					(unit 1)
				)
			)
		)
	)
	(symbol
		(lib_id "antmicroResistors0402:R_2k2_0402")
		(at 93.98 151.13 270)
		(unit 1)
		(exclude_from_sim no)
		(in_bom yes)
		(on_board yes)
		(dnp no)
		(property "Reference" "R164"
			(at 92.964 146.558 0)
			(effects
				(font
					(size 1.27 1.27)
					(thickness 0.15)
				)
				(justify left)
			)
		)
		(property "Value" "R_2k2_0402"
			(at 81.28 171.45 0)
			(effects
				(font
					(size 1.27 1.27)
					(thickness 0.15)
				)
				(justify left bottom)
				(hide yes)
			)
		)
		(property "Footprint" "antmicro-footprints:R_0402_1005Metric"
			(at 78.74 171.45 0)
			(effects
				(font
					(size 1.27 1.27)
					(thickness 0.15)
				)
				(justify left bottom)
				(hide yes)
			)
		)
		(property "Datasheet" "https://www.bourns.com/docs/product-datasheets/cr.pdf"
			(at 76.2 171.45 0)
			(effects
				(font
					(size 1.27 1.27)
					(thickness 0.15)
				)
				(justify left bottom)
				(hide yes)
			)
		)
		(property "Description" "SMD Chip Resistor, 2.2 kohm, ± 1%, 62.5 mW, 0402 [1005 Metric], Thick Film, General Purpose"
			(at 63.5 171.45 0)
			(effects
				(font
					(size 1.27 1.27)
				)
				(justify left bottom)
				(hide yes)
			)
		)
		(property "MPN" "CR0402-FX-2201GLF"
			(at 73.66 171.45 0)
			(effects
				(font
					(size 1.27 1.27)
					(thickness 0.15)
				)
				(justify left bottom)
				(hide yes)
			)
		)
		(property "Manufacturer" "Bourns"
			(at 71.12 171.45 0)
			(effects
				(font
					(size 1.27 1.27)
					(thickness 0.15)
				)
				(justify left bottom)
				(hide yes)
			)
		)
		(property "License" "Apache-2.0"
			(at 68.58 171.45 0)
			(effects
				(font
					(size 1.27 1.27)
					(thickness 0.15)
				)
				(justify left bottom)
				(hide yes)
			)
		)
		(property "Author" "Antmicro"
			(at 66.04 171.45 0)
			(effects
				(font
					(size 1.27 1.27)
					(thickness 0.15)
				)
				(justify left bottom)
				(hide yes)
			)
		)
		(property "Val" "2k2"
			(at 92.964 155.702 0)
			(effects
				(font
					(size 1.27 1.27)
					(thickness 0.15)
				)
				(justify left)
			)
		)
		(property "Tolerance" "1%"
			(at 83.82 171.45 0)
			(effects
				(font
					(size 1.27 1.27)
				)
				(justify left bottom)
				(hide yes)
			)
		)
		(pin "1"
		)
		(pin "2"
		)
		(instances
			(project "jetson-agx-thor-baseboard"
				(path ""
					(reference "R164")
					(unit 1)
				)
			)
		)
	)
	(symbol
		(lib_id "antmicroCapacitors0402:C_100n_0402")
		(at 212.09 203.2 90)
		(mirror x)
		(unit 1)
		(exclude_from_sim no)
		(in_bom yes)
		(on_board yes)
		(dnp no)
		(property "Reference" "C158"
			(at 213.995 204.47 90)
			(effects
				(font
					(size 1.27 1.27)
				)
				(justify right)
			)
		)
		(property "Value" "C_100n_0402"
			(at 222.25 223.52 0)
			(effects
				(font
					(size 1.27 1.27)
					(thickness 0.15)
				)
				(justify left bottom)
				(hide yes)
			)
		)
		(property "Footprint" "antmicro-footprints:C_0402_1005Metric"
			(at 224.79 223.52 0)
			(effects
				(font
					(size 1.27 1.27)
					(thickness 0.15)
				)
				(justify left bottom)
				(hide yes)
			)
		)
		(property "Datasheet" "https://www.murata.com/products/productdetail?partno=GRM155R61H104KE14%23"
			(at 227.33 223.52 0)
			(effects
				(font
					(size 1.27 1.27)
					(thickness 0.15)
				)
				(justify left bottom)
				(hide yes)
			)
		)
		(property "Description" "SMD Multilayer Ceramic Capacitor, 0.1 µF, 50 V, 0402 [1005 Metric], ± 10%, X5R, GRM Series"
			(at 212.09 203.2 0)
			(effects
				(font
					(size 1.27 1.27)
				)
				(hide yes)
			)
		)
		(property "Manufacturer" "Murata"
			(at 232.41 223.52 0)
			(effects
				(font
					(size 1.27 1.27)
					(thickness 0.15)
				)
				(justify left bottom)
				(hide yes)
			)
		)
		(property "MPN" "GRM155R61H104KE14D"
			(at 229.87 223.52 0)
			(effects
				(font
					(size 1.27 1.27)
					(thickness 0.15)
				)
				(justify left bottom)
				(hide yes)
			)
		)
		(property "Val" "100n"
			(at 213.995 207.01 90)
			(effects
				(font
					(size 1.27 1.27)
					(thickness 0.15)
				)
				(justify right)
			)
		)
		(property "License" "Apache-2.0"
			(at 234.95 223.52 0)
			(effects
				(font
					(size 1.27 1.27)
					(thickness 0.15)
				)
				(justify left bottom)
				(hide yes)
			)
		)
		(property "Author" "Antmicro"
			(at 237.49 223.52 0)
			(effects
				(font
					(size 1.27 1.27)
					(thickness 0.15)
				)
				(justify left bottom)
				(hide yes)
			)
		)
		(property "Voltage" "50V"
			(at 240.03 223.52 0)
			(effects
				(font
					(size 1.27 1.27)
				)
				(justify left bottom)
				(hide yes)
			)
		)
		(property "Dielectric" "X5R"
			(at 242.57 223.52 0)
			(effects
				(font
					(size 1.27 1.27)
				)
				(justify left bottom)
				(hide yes)
			)
		)
		(pin "1"
		)
		(pin "2"
		)
		(instances
			(project "jetson-agx-thor-baseboard"
				(path ""
					(reference "C158")
					(unit 1)
				)
			)
		)
	)
	(symbol
		(lib_id "antmicroResistors0402:R_200R_0402")
		(at 323.85 161.29 90)
		(unit 1)
		(exclude_from_sim no)
		(in_bom yes)
		(on_board yes)
		(dnp no)
		(fields_autoplaced yes)
		(property "Reference" "R177"
			(at 321.31 157.48 90)
			(effects
				(font
					(size 1.27 1.27)
				)
				(justify left)
			)
		)
		(property "Value" "R_200R_0402"
			(at 336.55 140.97 0)
			(effects
				(font
					(size 1.27 1.27)
					(thickness 0.15)
				)
				(justify left bottom)
				(hide yes)
			)
		)
		(property "Footprint" "antmicro-footprints:R_0402_1005Metric"
			(at 339.09 140.97 0)
			(effects
				(font
					(size 1.27 1.27)
					(thickness 0.15)
				)
				(justify left bottom)
				(hide yes)
			)
		)
		(property "Datasheet" "https://www.bourns.com/docs/product-datasheets/cr.pdf"
			(at 341.63 140.97 0)
			(effects
				(font
					(size 1.27 1.27)
					(thickness 0.15)
				)
				(justify left bottom)
				(hide yes)
			)
		)
		(property "Description" "SMD Chip Resistor, 200 ohm, ± 1%, 62.5 mW, 0402 [1005 Metric], Thick Film, General Purpose"
			(at 323.85 161.29 0)
			(effects
				(font
					(size 1.27 1.27)
				)
				(hide yes)
			)
		)
		(property "Manufacturer" "Bourns"
			(at 346.71 140.97 0)
			(effects
				(font
					(size 1.27 1.27)
					(thickness 0.15)
				)
				(justify left bottom)
				(hide yes)
			)
		)
		(property "MPN" "CR0402-FX-2000GLF"
			(at 344.17 140.97 0)
			(effects
				(font
					(size 1.27 1.27)
					(thickness 0.15)
				)
				(justify left bottom)
				(hide yes)
			)
		)
		(property "Val" "200R"
			(at 321.31 160.02 90)
			(effects
				(font
					(size 1.27 1.27)
					(thickness 0.15)
				)
				(justify left)
			)
		)
		(property "License" "Apache-2.0"
			(at 349.25 140.97 0)
			(effects
				(font
					(size 1.27 1.27)
					(thickness 0.15)
				)
				(justify left bottom)
				(hide yes)
			)
		)
		(property "Author" "Antmicro"
			(at 351.79 140.97 0)
			(effects
				(font
					(size 1.27 1.27)
					(thickness 0.15)
				)
				(justify left bottom)
				(hide yes)
			)
		)
		(property "Tolerance" "1%"
			(at 334.01 140.97 0)
			(effects
				(font
					(size 1.27 1.27)
				)
				(justify left bottom)
				(hide yes)
			)
		)
		(pin "1"
		)
		(pin "2"
		)
		(instances
			(project "jetson-agx-thor-baseboard"
				(path ""
					(reference "R177")
					(unit 1)
				)
			)
		)
	)
	(symbol
		(lib_id "antmicropower:+3V3")
		(at 92.71 200.66 0)
		(unit 1)
		(exclude_from_sim no)
		(in_bom yes)
		(on_board yes)
		(dnp no)
		(property "Reference" "#PWR0291"
			(at 92.71 204.47 0)
			(effects
				(font
					(size 1.27 1.27)
				)
				(justify left bottom)
				(hide yes)
			)
		)
		(property "Value" "+3V3"
			(at 89.535 196.85 0)
			(effects
				(font
					(size 1.27 1.27)
					(thickness 0.15)
				)
				(justify left)
			)
		)
		(property "Footprint" ""
			(at 107.95 208.28 0)
			(effects
				(font
					(size 1.27 1.27)
					(thickness 0.15)
				)
				(justify left bottom)
				(hide yes)
			)
		)
		(property "Datasheet" ""
			(at 107.95 210.82 0)
			(effects
				(font
					(size 1.27 1.27)
					(thickness 0.15)
				)
				(justify left bottom)
				(hide yes)
			)
		)
		(property "Description" ""
			(at 92.71 200.66 0)
			(effects
				(font
					(size 1.27 1.27)
				)
				(hide yes)
			)
		)
		(property "Author" "Antmicro"
			(at 107.95 203.2 0)
			(effects
				(font
					(size 1.27 1.27)
					(thickness 0.15)
				)
				(justify left bottom)
				(hide yes)
			)
		)
		(property "License" "Apache-2.0"
			(at 107.95 205.74 0)
			(effects
				(font
					(size 1.27 1.27)
					(thickness 0.15)
				)
				(justify left bottom)
				(hide yes)
			)
		)
		(pin "1"
		)
		(instances
			(project "jetson-agx-thor-baseboard"
				(path ""
					(reference "#PWR0291")
					(unit 1)
				)
			)
		)
	)
	(symbol
		(lib_id "antmicroResistors0402:R_4k7_0402")
		(at 149.86 252.73 90)
		(unit 1)
		(exclude_from_sim no)
		(in_bom yes)
		(on_board yes)
		(dnp no)
		(property "Reference" "R173"
			(at 151.13 248.92 90)
			(effects
				(font
					(size 1.27 1.27)
				)
				(justify right)
			)
		)
		(property "Value" "R_4k7_0402"
			(at 162.56 232.41 0)
			(effects
				(font
					(size 1.27 1.27)
					(thickness 0.15)
				)
				(justify left bottom)
				(hide yes)
			)
		)
		(property "Footprint" "antmicro-footprints:R_0402_1005Metric"
			(at 165.1 232.41 0)
			(effects
				(font
					(size 1.27 1.27)
					(thickness 0.15)
				)
				(justify left bottom)
				(hide yes)
			)
		)
		(property "Datasheet" "https://www.bourns.com/docs/product-datasheets/cr.pdf"
			(at 167.64 232.41 0)
			(effects
				(font
					(size 1.27 1.27)
					(thickness 0.15)
				)
				(justify left bottom)
				(hide yes)
			)
		)
		(property "Description" "SMD Chip Resistor, 4.7 kohm, ± 1%, 62.5 mW, 0402 [1005 Metric], Thick Film, General Purpose"
			(at 149.86 252.73 0)
			(effects
				(font
					(size 1.27 1.27)
				)
				(hide yes)
			)
		)
		(property "Manufacturer" "Bourns"
			(at 172.72 232.41 0)
			(effects
				(font
					(size 1.27 1.27)
					(thickness 0.15)
				)
				(justify left bottom)
				(hide yes)
			)
		)
		(property "MPN" "CR0402-FX-4701GLF"
			(at 170.18 232.41 0)
			(effects
				(font
					(size 1.27 1.27)
					(thickness 0.15)
				)
				(justify left bottom)
				(hide yes)
			)
		)
		(property "Val" "4k7"
			(at 151.13 251.46 90)
			(effects
				(font
					(size 1.27 1.27)
					(thickness 0.15)
				)
				(justify right)
			)
		)
		(property "License" "Apache-2.0"
			(at 175.26 232.41 0)
			(effects
				(font
					(size 1.27 1.27)
					(thickness 0.15)
				)
				(justify left bottom)
				(hide yes)
			)
		)
		(property "Author" "Antmicro"
			(at 177.8 232.41 0)
			(effects
				(font
					(size 1.27 1.27)
					(thickness 0.15)
				)
				(justify left bottom)
				(hide yes)
			)
		)
		(property "Tolerance" "1%"
			(at 160.02 232.41 0)
			(effects
				(font
					(size 1.27 1.27)
				)
				(justify left bottom)
				(hide yes)
			)
		)
		(pin "1"
		)
		(pin "2"
		)
		(instances
			(project "jetson-agx-thor-baseboard"
				(path ""
					(reference "R173")
					(unit 1)
				)
			)
		)
	)
	(symbol
		(lib_id "antmicropower:GND")
		(at 251.46 168.91 0)
		(unit 1)
		(exclude_from_sim no)
		(in_bom yes)
		(on_board yes)
		(dnp no)
		(property "Reference" "#PWR0325"
			(at 251.46 175.26 0)
			(effects
				(font
					(size 1.27 1.27)
				)
				(justify left bottom)
				(hide yes)
			)
		)
		(property "Value" "GND"
			(at 251.46 172.72 0)
			(effects
				(font
					(size 1.27 1.27)
					(thickness 0.15)
				)
			)
		)
		(property "Footprint" ""
			(at 260.35 176.53 0)
			(effects
				(font
					(size 1.27 1.27)
					(thickness 0.15)
				)
				(justify left bottom)
				(hide yes)
			)
		)
		(property "Datasheet" ""
			(at 260.35 181.61 0)
			(effects
				(font
					(size 1.27 1.27)
					(thickness 0.15)
				)
				(justify left bottom)
				(hide yes)
			)
		)
		(property "Description" ""
			(at 251.46 168.91 0)
			(effects
				(font
					(size 1.27 1.27)
				)
				(hide yes)
			)
		)
		(property "Author" "Antmicro"
			(at 260.35 176.53 0)
			(effects
				(font
					(size 1.27 1.27)
					(thickness 0.15)
				)
				(justify left bottom)
				(hide yes)
			)
		)
		(property "License" "Apache-2.0"
			(at 260.35 179.07 0)
			(effects
				(font
					(size 1.27 1.27)
					(thickness 0.15)
				)
				(justify left bottom)
				(hide yes)
			)
		)
		(pin "1"
		)
		(instances
			(project "jetson-agx-thor-baseboard"
				(path ""
					(reference "#PWR0325")
					(unit 1)
				)
			)
		)
	)
	(symbol
		(lib_id "antmicroResistors0402:R_0R_0402")
		(at 349.25 132.08 0)
		(unit 1)
		(exclude_from_sim no)
		(in_bom yes)
		(on_board yes)
		(dnp no)
		(property "Reference" "R396"
			(at 356.108 131.064 0)
			(effects
				(font
					(size 1.27 1.27)
					(thickness 0.15)
				)
			)
		)
		(property "Value" "R_0R_0402"
			(at 369.57 144.78 0)
			(effects
				(font
					(size 1.27 1.27)
					(thickness 0.15)
				)
				(justify left bottom)
				(hide yes)
			)
		)
		(property "Footprint" "antmicro-footprints:R_0402_1005Metric"
			(at 369.57 147.32 0)
			(effects
				(font
					(size 1.27 1.27)
					(thickness 0.15)
				)
				(justify left bottom)
				(hide yes)
			)
		)
		(property "Datasheet" "https://industrial.panasonic.com/cdbs/www-data/pdf/RDA0000/AOA0000C301.pdf"
			(at 369.57 149.86 0)
			(effects
				(font
					(size 1.27 1.27)
					(thickness 0.15)
				)
				(justify left bottom)
				(hide yes)
			)
		)
		(property "Description" "SMD Chip Resistor, Jumper, 0 ohm, 100 mW, 0402 [1005 Metric], Thick Film, General Purpose"
			(at 369.57 165.1 0)
			(effects
				(font
					(size 1.27 1.27)
				)
				(justify left bottom)
				(hide yes)
			)
		)
		(property "MPN" "ERJ2GE0R00X"
			(at 369.57 152.4 0)
			(effects
				(font
					(size 1.27 1.27)
					(thickness 0.15)
				)
				(justify left bottom)
				(hide yes)
			)
		)
		(property "Manufacturer" "Panasonic"
			(at 369.57 154.94 0)
			(effects
				(font
					(size 1.27 1.27)
					(thickness 0.15)
				)
				(justify left bottom)
				(hide yes)
			)
		)
		(property "License" "Apache-2.0"
			(at 369.57 157.48 0)
			(effects
				(font
					(size 1.27 1.27)
					(thickness 0.15)
				)
				(justify left bottom)
				(hide yes)
			)
		)
		(property "Author" "Antmicro"
			(at 369.57 160.02 0)
			(effects
				(font
					(size 1.27 1.27)
					(thickness 0.15)
				)
				(justify left bottom)
				(hide yes)
			)
		)
		(property "Val" "0R"
			(at 348.488 131.064 0)
			(effects
				(font
					(size 1.27 1.27)
					(thickness 0.15)
				)
			)
		)
		(property "Tolerance" "~"
			(at 369.57 142.24 0)
			(effects
				(font
					(size 1.27 1.27)
				)
				(justify left bottom)
				(hide yes)
			)
		)
		(property "Current" "1A"
			(at 369.57 162.56 0)
			(effects
				(font
					(size 1.27 1.27)
					(thickness 0.15)
				)
				(justify left bottom)
				(hide yes)
			)
		)
		(pin "2"
		)
		(pin "1"
		)
		(instances
			(project "jetson-agx-thor-baseboard"
				(path ""
					(reference "R396")
					(unit 1)
				)
			)
		)
	)
	(symbol
		(lib_id "antmicroResistors0402:R_0R_0402")
		(at 76.2 140.97 90)
		(unit 1)
		(exclude_from_sim no)
		(in_bom yes)
		(on_board yes)
		(dnp no)
		(property "Reference" "R158"
			(at 74.93 137.16 90)
			(effects
				(font
					(size 1.27 1.27)
				)
				(justify left)
			)
		)
		(property "Value" "R_0R_0402"
			(at 88.9 120.65 0)
			(effects
				(font
					(size 1.27 1.27)
					(thickness 0.15)
				)
				(justify left bottom)
				(hide yes)
			)
		)
		(property "Footprint" "antmicro-footprints:R_0402_1005Metric"
			(at 91.44 120.65 0)
			(effects
				(font
					(size 1.27 1.27)
					(thickness 0.15)
				)
				(justify left bottom)
				(hide yes)
			)
		)
		(property "Datasheet" "https://industrial.panasonic.com/cdbs/www-data/pdf/RDA0000/AOA0000C301.pdf"
			(at 93.98 120.65 0)
			(effects
				(font
					(size 1.27 1.27)
					(thickness 0.15)
				)
				(justify left bottom)
				(hide yes)
			)
		)
		(property "Description" "SMD Chip Resistor, Jumper, 0 ohm, 100 mW, 0402 [1005 Metric], Thick Film, General Purpose"
			(at 76.2 140.97 0)
			(effects
				(font
					(size 1.27 1.27)
				)
				(hide yes)
			)
		)
		(property "Manufacturer" "Panasonic"
			(at 99.06 120.65 0)
			(effects
				(font
					(size 1.27 1.27)
					(thickness 0.15)
				)
				(justify left bottom)
				(hide yes)
			)
		)
		(property "MPN" "ERJ2GE0R00X"
			(at 96.52 120.65 0)
			(effects
				(font
					(size 1.27 1.27)
					(thickness 0.15)
				)
				(justify left bottom)
				(hide yes)
			)
		)
		(property "Val" "0R"
			(at 74.93 139.7 90)
			(effects
				(font
					(size 1.27 1.27)
					(thickness 0.15)
				)
				(justify left)
			)
		)
		(property "License" "Apache-2.0"
			(at 101.6 120.65 0)
			(effects
				(font
					(size 1.27 1.27)
					(thickness 0.15)
				)
				(justify left bottom)
				(hide yes)
			)
		)
		(property "Author" "Antmicro"
			(at 104.14 120.65 0)
			(effects
				(font
					(size 1.27 1.27)
					(thickness 0.15)
				)
				(justify left bottom)
				(hide yes)
			)
		)
		(property "Tolerance" "~"
			(at 86.36 120.65 0)
			(effects
				(font
					(size 1.27 1.27)
				)
				(justify left bottom)
				(hide yes)
			)
		)
		(property "Current" "1A"
			(at 106.68 120.65 0)
			(effects
				(font
					(size 1.27 1.27)
					(thickness 0.15)
				)
				(justify left bottom)
				(hide yes)
			)
		)
		(pin "1"
		)
		(pin "2"
		)
		(instances
			(project "jetson-agx-thor-baseboard"
				(path ""
					(reference "R158")
					(unit 1)
				)
			)
		)
	)
	(symbol
		(lib_id "antmicroResistors0402:R_2k2_0402")
		(at 128.27 151.13 270)
		(unit 1)
		(exclude_from_sim no)
		(in_bom yes)
		(on_board yes)
		(dnp no)
		(property "Reference" "R171"
			(at 127.254 146.558 0)
			(effects
				(font
					(size 1.27 1.27)
					(thickness 0.15)
				)
				(justify left)
			)
		)
		(property "Value" "R_2k2_0402"
			(at 115.57 171.45 0)
			(effects
				(font
					(size 1.27 1.27)
					(thickness 0.15)
				)
				(justify left bottom)
				(hide yes)
			)
		)
		(property "Footprint" "antmicro-footprints:R_0402_1005Metric"
			(at 113.03 171.45 0)
			(effects
				(font
					(size 1.27 1.27)
					(thickness 0.15)
				)
				(justify left bottom)
				(hide yes)
			)
		)
		(property "Datasheet" "https://www.bourns.com/docs/product-datasheets/cr.pdf"
			(at 110.49 171.45 0)
			(effects
				(font
					(size 1.27 1.27)
					(thickness 0.15)
				)
				(justify left bottom)
				(hide yes)
			)
		)
		(property "Description" "SMD Chip Resistor, 2.2 kohm, ± 1%, 62.5 mW, 0402 [1005 Metric], Thick Film, General Purpose"
			(at 97.79 171.45 0)
			(effects
				(font
					(size 1.27 1.27)
				)
				(justify left bottom)
				(hide yes)
			)
		)
		(property "MPN" "CR0402-FX-2201GLF"
			(at 107.95 171.45 0)
			(effects
				(font
					(size 1.27 1.27)
					(thickness 0.15)
				)
				(justify left bottom)
				(hide yes)
			)
		)
		(property "Manufacturer" "Bourns"
			(at 105.41 171.45 0)
			(effects
				(font
					(size 1.27 1.27)
					(thickness 0.15)
				)
				(justify left bottom)
				(hide yes)
			)
		)
		(property "License" "Apache-2.0"
			(at 102.87 171.45 0)
			(effects
				(font
					(size 1.27 1.27)
					(thickness 0.15)
				)
				(justify left bottom)
				(hide yes)
			)
		)
		(property "Author" "Antmicro"
			(at 100.33 171.45 0)
			(effects
				(font
					(size 1.27 1.27)
					(thickness 0.15)
				)
				(justify left bottom)
				(hide yes)
			)
		)
		(property "Val" "2k2"
			(at 127.254 155.702 0)
			(effects
				(font
					(size 1.27 1.27)
					(thickness 0.15)
				)
				(justify left)
			)
		)
		(property "Tolerance" "1%"
			(at 118.11 171.45 0)
			(effects
				(font
					(size 1.27 1.27)
				)
				(justify left bottom)
				(hide yes)
			)
		)
		(pin "1"
		)
		(pin "2"
		)
		(instances
			(project "jetson-agx-thor-baseboard"
				(path ""
					(reference "R171")
					(unit 1)
				)
			)
		)
	)
	(symbol
		(lib_id "antmicroLogicTranslatorsLevelShifters:NTS0102_XSON")
		(at 342.9 209.55 0)
		(unit 1)
		(exclude_from_sim no)
		(in_bom yes)
		(on_board yes)
		(dnp no)
		(property "Reference" "U48"
			(at 353.06 203.2 0)
			(effects
				(font
					(size 1.27 1.27)
				)
			)
		)
		(property "Value" "NTS0102_XSON"
			(at 378.46 217.17 0)
			(effects
				(font
					(size 1.27 1.27)
					(thickness 0.15)
				)
				(justify left bottom)
				(hide yes)
			)
		)
		(property "Footprint" "antmicro-footprints:XSON-8_1x1.95mm_P0.5mm"
			(at 378.46 219.71 0)
			(effects
				(font
					(size 1.27 1.27)
					(thickness 0.15)
				)
				(justify left bottom)
				(hide yes)
			)
		)
		(property "Datasheet" "http://www.farnell.com/datasheets/1760723.pdf"
			(at 378.46 222.25 0)
			(effects
				(font
					(size 1.27 1.27)
					(thickness 0.15)
				)
				(justify left bottom)
				(hide yes)
			)
		)
		(property "Description" "Transceiver, 1.65 V to 3.6 V, XSON-8"
			(at 342.9 209.55 0)
			(effects
				(font
					(size 1.27 1.27)
				)
				(hide yes)
			)
		)
		(property "MPN" "NTS0102GT"
			(at 353.06 205.74 0)
			(effects
				(font
					(size 1.27 1.27)
					(thickness 0.15)
				)
			)
		)
		(property "Manufacturer" "NXP"
			(at 378.46 224.79 0)
			(effects
				(font
					(size 1.27 1.27)
					(thickness 0.15)
				)
				(justify left bottom)
				(hide yes)
			)
		)
		(property "Author" "Antmicro"
			(at 378.46 227.33 0)
			(effects
				(font
					(size 1.27 1.27)
					(thickness 0.15)
				)
				(justify left bottom)
				(hide yes)
			)
		)
		(property "License" "Apache-2.0"
			(at 378.46 229.87 0)
			(effects
				(font
					(size 1.27 1.27)
					(thickness 0.15)
				)
				(justify left bottom)
				(hide yes)
			)
		)
		(pin "1"
		)
		(pin "2"
		)
		(pin "3"
		)
		(pin "4"
		)
		(pin "5"
		)
		(pin "6"
		)
		(pin "7"
		)
		(pin "8"
		)
		(instances
			(project "jetson-agx-thor-baseboard"
				(path ""
					(reference "U48")
					(unit 1)
				)
			)
		)
	)
	(symbol
		(lib_id "antmicropower:+3V3")
		(at 372.11 224.79 0)
		(unit 1)
		(exclude_from_sim no)
		(in_bom yes)
		(on_board yes)
		(dnp no)
		(property "Reference" "#PWR0337"
			(at 372.11 228.6 0)
			(effects
				(font
					(size 1.27 1.27)
				)
				(justify left bottom)
				(hide yes)
			)
		)
		(property "Value" "+3V3"
			(at 368.935 220.98 0)
			(effects
				(font
					(size 1.27 1.27)
					(thickness 0.15)
				)
				(justify left)
			)
		)
		(property "Footprint" ""
			(at 387.35 232.41 0)
			(effects
				(font
					(size 1.27 1.27)
					(thickness 0.15)
				)
				(justify left bottom)
				(hide yes)
			)
		)
		(property "Datasheet" ""
			(at 387.35 234.95 0)
			(effects
				(font
					(size 1.27 1.27)
					(thickness 0.15)
				)
				(justify left bottom)
				(hide yes)
			)
		)
		(property "Description" ""
			(at 372.11 224.79 0)
			(effects
				(font
					(size 1.27 1.27)
				)
				(hide yes)
			)
		)
		(property "Author" "Antmicro"
			(at 387.35 227.33 0)
			(effects
				(font
					(size 1.27 1.27)
					(thickness 0.15)
				)
				(justify left bottom)
				(hide yes)
			)
		)
		(property "License" "Apache-2.0"
			(at 387.35 229.87 0)
			(effects
				(font
					(size 1.27 1.27)
					(thickness 0.15)
				)
				(justify left bottom)
				(hide yes)
			)
		)
		(pin "1"
		)
		(instances
			(project "jetson-agx-thor-baseboard"
				(path ""
					(reference "#PWR0337")
					(unit 1)
				)
			)
		)
	)
	(symbol
		(lib_id "antmicroResistors0402:R_0R_0402")
		(at 349.25 129.54 0)
		(unit 1)
		(exclude_from_sim no)
		(in_bom yes)
		(on_board yes)
		(dnp no)
		(property "Reference" "R395"
			(at 356.108 128.524 0)
			(effects
				(font
					(size 1.27 1.27)
					(thickness 0.15)
				)
			)
		)
		(property "Value" "R_0R_0402"
			(at 369.57 142.24 0)
			(effects
				(font
					(size 1.27 1.27)
					(thickness 0.15)
				)
				(justify left bottom)
				(hide yes)
			)
		)
		(property "Footprint" "antmicro-footprints:R_0402_1005Metric"
			(at 369.57 144.78 0)
			(effects
				(font
					(size 1.27 1.27)
					(thickness 0.15)
				)
				(justify left bottom)
				(hide yes)
			)
		)
		(property "Datasheet" "https://industrial.panasonic.com/cdbs/www-data/pdf/RDA0000/AOA0000C301.pdf"
			(at 369.57 147.32 0)
			(effects
				(font
					(size 1.27 1.27)
					(thickness 0.15)
				)
				(justify left bottom)
				(hide yes)
			)
		)
		(property "Description" "SMD Chip Resistor, Jumper, 0 ohm, 100 mW, 0402 [1005 Metric], Thick Film, General Purpose"
			(at 369.57 162.56 0)
			(effects
				(font
					(size 1.27 1.27)
				)
				(justify left bottom)
				(hide yes)
			)
		)
		(property "MPN" "ERJ2GE0R00X"
			(at 369.57 149.86 0)
			(effects
				(font
					(size 1.27 1.27)
					(thickness 0.15)
				)
				(justify left bottom)
				(hide yes)
			)
		)
		(property "Manufacturer" "Panasonic"
			(at 369.57 152.4 0)
			(effects
				(font
					(size 1.27 1.27)
					(thickness 0.15)
				)
				(justify left bottom)
				(hide yes)
			)
		)
		(property "License" "Apache-2.0"
			(at 369.57 154.94 0)
			(effects
				(font
					(size 1.27 1.27)
					(thickness 0.15)
				)
				(justify left bottom)
				(hide yes)
			)
		)
		(property "Author" "Antmicro"
			(at 369.57 157.48 0)
			(effects
				(font
					(size 1.27 1.27)
					(thickness 0.15)
				)
				(justify left bottom)
				(hide yes)
			)
		)
		(property "Val" "0R"
			(at 348.488 128.524 0)
			(effects
				(font
					(size 1.27 1.27)
					(thickness 0.15)
				)
			)
		)
		(property "Tolerance" "~"
			(at 369.57 139.7 0)
			(effects
				(font
					(size 1.27 1.27)
				)
				(justify left bottom)
				(hide yes)
			)
		)
		(property "Current" "1A"
			(at 369.57 160.02 0)
			(effects
				(font
					(size 1.27 1.27)
					(thickness 0.15)
				)
				(justify left bottom)
				(hide yes)
			)
		)
		(pin "2"
		)
		(pin "1"
		)
		(instances
			(project ""
				(path ""
					(reference "R395")
					(unit 1)
				)
			)
		)
	)
	(symbol
		(lib_id "antmicropower:GND")
		(at 259.08 254 0)
		(unit 1)
		(exclude_from_sim no)
		(in_bom yes)
		(on_board yes)
		(dnp no)
		(property "Reference" "#PWR0320"
			(at 259.08 260.35 0)
			(effects
				(font
					(size 1.27 1.27)
				)
				(justify left bottom)
				(hide yes)
			)
		)
		(property "Value" "GND"
			(at 259.08 257.81 0)
			(effects
				(font
					(size 1.27 1.27)
					(thickness 0.15)
				)
			)
		)
		(property "Footprint" ""
			(at 267.97 261.62 0)
			(effects
				(font
					(size 1.27 1.27)
					(thickness 0.15)
				)
				(justify left bottom)
				(hide yes)
			)
		)
		(property "Datasheet" ""
			(at 267.97 266.7 0)
			(effects
				(font
					(size 1.27 1.27)
					(thickness 0.15)
				)
				(justify left bottom)
				(hide yes)
			)
		)
		(property "Description" ""
			(at 259.08 254 0)
			(effects
				(font
					(size 1.27 1.27)
				)
				(hide yes)
			)
		)
		(property "Author" "Antmicro"
			(at 267.97 261.62 0)
			(effects
				(font
					(size 1.27 1.27)
					(thickness 0.15)
				)
				(justify left bottom)
				(hide yes)
			)
		)
		(property "License" "Apache-2.0"
			(at 267.97 264.16 0)
			(effects
				(font
					(size 1.27 1.27)
					(thickness 0.15)
				)
				(justify left bottom)
				(hide yes)
			)
		)
		(pin "1"
		)
		(instances
			(project "jetson-agx-thor-baseboard"
				(path ""
					(reference "#PWR0320")
					(unit 1)
				)
			)
		)
	)
	(symbol
		(lib_id "antmicroTestPoints:TP_0.75mm_SMD")
		(at 147.32 93.98 0)
		(unit 1)
		(exclude_from_sim no)
		(in_bom no)
		(on_board yes)
		(dnp no)
		(property "Reference" "TP24"
			(at 151.13 93.9799 0)
			(effects
				(font
					(size 1.27 1.27)
				)
				(justify left)
			)
		)
		(property "Value" "TP_0.75mm_SMD"
			(at 157.48 97.79 0)
			(effects
				(font
					(size 1.27 1.27)
					(thickness 0.15)
				)
				(justify left bottom)
				(hide yes)
			)
		)
		(property "Footprint" "antmicro-footprints:TP_SMD_0.75mm"
			(at 157.48 100.33 0)
			(effects
				(font
					(size 1.27 1.27)
					(thickness 0.15)
				)
				(justify left bottom)
				(hide yes)
			)
		)
		(property "Datasheet" ""
			(at 165.1 106.68 0)
			(effects
				(font
					(size 1.27 1.27)
					(thickness 0.15)
				)
				(justify left bottom)
				(hide yes)
			)
		)
		(property "Description" "SMT test point"
			(at 147.32 93.98 0)
			(effects
				(font
					(size 1.27 1.27)
				)
				(hide yes)
			)
		)
		(property "MPN" ""
			(at 158.115 105.41 0)
			(effects
				(font
					(size 1.27 1.27)
					(thickness 0.15)
				)
				(justify left bottom)
				(hide yes)
			)
		)
		(property "Manufacturer" ""
			(at 158.115 100.33 0)
			(effects
				(font
					(size 1.27 1.27)
					(thickness 0.15)
				)
				(justify left bottom)
				(hide yes)
			)
		)
		(property "Author" "Antmicro"
			(at 157.48 102.87 0)
			(effects
				(font
					(size 1.27 1.27)
					(thickness 0.15)
				)
				(justify left bottom)
				(hide yes)
			)
		)
		(property "License" "Apache-2.0"
			(at 157.48 105.41 0)
			(effects
				(font
					(size 1.27 1.27)
					(thickness 0.15)
				)
				(justify left bottom)
				(hide yes)
			)
		)
		(pin "1"
		)
		(instances
			(project "jetson-agx-thor-baseboard"
				(path ""
					(reference "TP24")
					(unit 1)
				)
			)
		)
	)
	(symbol
		(lib_id "antmicropower:+1V8")
		(at 93.98 80.01 0)
		(unit 1)
		(exclude_from_sim no)
		(in_bom yes)
		(on_board yes)
		(dnp no)
		(property "Reference" "#PWR0293"
			(at 93.98 83.82 0)
			(effects
				(font
					(size 1.27 1.27)
				)
				(justify left bottom)
				(hide yes)
			)
		)
		(property "Value" "+1V8"
			(at 90.805 76.2 0)
			(effects
				(font
					(size 1.27 1.27)
					(thickness 0.15)
				)
				(justify left)
			)
		)
		(property "Footprint" ""
			(at 109.22 87.63 0)
			(effects
				(font
					(size 1.27 1.27)
					(thickness 0.15)
				)
				(justify left bottom)
				(hide yes)
			)
		)
		(property "Datasheet" ""
			(at 109.22 90.17 0)
			(effects
				(font
					(size 1.27 1.27)
					(thickness 0.15)
				)
				(justify left bottom)
				(hide yes)
			)
		)
		(property "Description" ""
			(at 93.98 80.01 0)
			(effects
				(font
					(size 1.27 1.27)
				)
				(hide yes)
			)
		)
		(property "Author" "Antmicro"
			(at 109.22 85.09 0)
			(effects
				(font
					(size 1.27 1.27)
					(thickness 0.15)
				)
				(justify left bottom)
				(hide yes)
			)
		)
		(property "License" "Apache-2.0"
			(at 109.22 87.63 0)
			(effects
				(font
					(size 1.27 1.27)
					(thickness 0.15)
				)
				(justify left bottom)
				(hide yes)
			)
		)
		(pin "1"
		)
		(instances
			(project "jetson-agx-thor-baseboard"
				(path ""
					(reference "#PWR0293")
					(unit 1)
				)
			)
		)
	)
	(symbol
		(lib_id "antmicroResistors0402:R_4k7_0402")
		(at 259.08 219.71 90)
		(unit 1)
		(exclude_from_sim no)
		(in_bom yes)
		(on_board yes)
		(dnp no)
		(property "Reference" "R179"
			(at 260.35 215.9 90)
			(effects
				(font
					(size 1.27 1.27)
				)
				(justify right)
			)
		)
		(property "Value" "R_4k7_0402"
			(at 271.78 199.39 0)
			(effects
				(font
					(size 1.27 1.27)
					(thickness 0.15)
				)
				(justify left bottom)
				(hide yes)
			)
		)
		(property "Footprint" "antmicro-footprints:R_0402_1005Metric"
			(at 274.32 199.39 0)
			(effects
				(font
					(size 1.27 1.27)
					(thickness 0.15)
				)
				(justify left bottom)
				(hide yes)
			)
		)
		(property "Datasheet" "https://www.bourns.com/docs/product-datasheets/cr.pdf"
			(at 276.86 199.39 0)
			(effects
				(font
					(size 1.27 1.27)
					(thickness 0.15)
				)
				(justify left bottom)
				(hide yes)
			)
		)
		(property "Description" "SMD Chip Resistor, 4.7 kohm, ± 1%, 62.5 mW, 0402 [1005 Metric], Thick Film, General Purpose"
			(at 259.08 219.71 0)
			(effects
				(font
					(size 1.27 1.27)
				)
				(hide yes)
			)
		)
		(property "Manufacturer" "Bourns"
			(at 281.94 199.39 0)
			(effects
				(font
					(size 1.27 1.27)
					(thickness 0.15)
				)
				(justify left bottom)
				(hide yes)
			)
		)
		(property "MPN" "CR0402-FX-4701GLF"
			(at 279.4 199.39 0)
			(effects
				(font
					(size 1.27 1.27)
					(thickness 0.15)
				)
				(justify left bottom)
				(hide yes)
			)
		)
		(property "Val" "4k7"
			(at 260.35 218.44 90)
			(effects
				(font
					(size 1.27 1.27)
					(thickness 0.15)
				)
				(justify right)
			)
		)
		(property "License" "Apache-2.0"
			(at 284.48 199.39 0)
			(effects
				(font
					(size 1.27 1.27)
					(thickness 0.15)
				)
				(justify left bottom)
				(hide yes)
			)
		)
		(property "Author" "Antmicro"
			(at 287.02 199.39 0)
			(effects
				(font
					(size 1.27 1.27)
					(thickness 0.15)
				)
				(justify left bottom)
				(hide yes)
			)
		)
		(property "Tolerance" "1%"
			(at 269.24 199.39 0)
			(effects
				(font
					(size 1.27 1.27)
				)
				(justify left bottom)
				(hide yes)
			)
		)
		(pin "1"
		)
		(pin "2"
		)
		(instances
			(project "jetson-agx-thor-baseboard"
				(path ""
					(reference "R179")
					(unit 1)
				)
			)
		)
	)
	(symbol
		(lib_id "antmicroFCCConnectors:Conn_FFC_WE_68715014522")
		(at 364.49 33.02 0)
		(unit 1)
		(exclude_from_sim no)
		(in_bom yes)
		(on_board yes)
		(dnp no)
		(fields_autoplaced yes)
		(property "Reference" "J10"
			(at 373.38 97.155 0)
			(effects
				(font
					(size 1.27 1.27)
				)
				(justify left)
			)
		)
		(property "Value" "Conn_FFC_WE_68715014522"
			(at 383.54 40.64 0)
			(effects
				(font
					(size 1.27 1.27)
					(thickness 0.15)
				)
				(justify left bottom)
				(hide yes)
			)
		)
		(property "Footprint" "antmicro-footprints:Conn_FFC_WE_68715014x22"
			(at 383.54 43.18 0)
			(effects
				(font
					(size 1.27 1.27)
					(thickness 0.15)
				)
				(justify left bottom)
				(hide yes)
			)
		)
		(property "Datasheet" "https://www.we-online.com/components/products/datasheet/68715014522.pdf"
			(at 383.54 45.72 0)
			(effects
				(font
					(size 1.27 1.27)
					(thickness 0.15)
				)
				(justify left bottom)
				(hide yes)
			)
		)
		(property "Description" "FFC connector"
			(at 364.49 33.02 0)
			(effects
				(font
					(size 1.27 1.27)
				)
				(hide yes)
			)
		)
		(property "MPN" "68715014522"
			(at 373.38 99.695 0)
			(effects
				(font
					(size 1.27 1.27)
					(thickness 0.15)
				)
				(justify left)
			)
		)
		(property "Manufacturer" "Würth Elektronik"
			(at 383.54 50.8 0)
			(effects
				(font
					(size 1.27 1.27)
					(thickness 0.15)
				)
				(justify left bottom)
				(hide yes)
			)
		)
		(property "Author" "Antmicro"
			(at 383.54 53.34 0)
			(effects
				(font
					(size 1.27 1.27)
					(thickness 0.15)
				)
				(justify left bottom)
				(hide yes)
			)
		)
		(property "License" "Apache-2.0"
			(at 383.54 55.88 0)
			(effects
				(font
					(size 1.27 1.27)
					(thickness 0.15)
				)
				(justify left bottom)
				(hide yes)
			)
		)
		(pin "1"
		)
		(pin "10"
		)
		(pin "11"
		)
		(pin "12"
		)
		(pin "13"
		)
		(pin "14"
		)
		(pin "15"
		)
		(pin "16"
		)
		(pin "17"
		)
		(pin "18"
		)
		(pin "19"
		)
		(pin "2"
		)
		(pin "20"
		)
		(pin "21"
		)
		(pin "22"
		)
		(pin "23"
		)
		(pin "24"
		)
		(pin "25"
		)
		(pin "26"
		)
		(pin "27"
		)
		(pin "28"
		)
		(pin "29"
		)
		(pin "3"
		)
		(pin "30"
		)
		(pin "31"
		)
		(pin "32"
		)
		(pin "33"
		)
		(pin "34"
		)
		(pin "35"
		)
		(pin "36"
		)
		(pin "37"
		)
		(pin "38"
		)
		(pin "39"
		)
		(pin "4"
		)
		(pin "40"
		)
		(pin "41"
		)
		(pin "42"
		)
		(pin "43"
		)
		(pin "44"
		)
		(pin "45"
		)
		(pin "46"
		)
		(pin "47"
		)
		(pin "48"
		)
		(pin "49"
		)
		(pin "5"
		)
		(pin "50"
		)
		(pin "6"
		)
		(pin "7"
		)
		(pin "8"
		)
		(pin "9"
		)
		(pin "MP2"
		)
		(pin "MP1"
		)
		(instances
			(project "jetson-agx-thor-baseboard"
				(path ""
					(reference "J10")
					(unit 1)
				)
			)
		)
	)
	(symbol
		(lib_id "antmicropower:GND")
		(at 135.89 254 0)
		(unit 1)
		(exclude_from_sim no)
		(in_bom yes)
		(on_board yes)
		(dnp no)
		(property "Reference" "#PWR0305"
			(at 135.89 260.35 0)
			(effects
				(font
					(size 1.27 1.27)
				)
				(justify left bottom)
				(hide yes)
			)
		)
		(property "Value" "GND"
			(at 135.89 257.81 0)
			(effects
				(font
					(size 1.27 1.27)
					(thickness 0.15)
				)
			)
		)
		(property "Footprint" ""
			(at 144.78 261.62 0)
			(effects
				(font
					(size 1.27 1.27)
					(thickness 0.15)
				)
				(justify left bottom)
				(hide yes)
			)
		)
		(property "Datasheet" ""
			(at 144.78 266.7 0)
			(effects
				(font
					(size 1.27 1.27)
					(thickness 0.15)
				)
				(justify left bottom)
				(hide yes)
			)
		)
		(property "Description" ""
			(at 135.89 254 0)
			(effects
				(font
					(size 1.27 1.27)
				)
				(hide yes)
			)
		)
		(property "Author" "Antmicro"
			(at 144.78 261.62 0)
			(effects
				(font
					(size 1.27 1.27)
					(thickness 0.15)
				)
				(justify left bottom)
				(hide yes)
			)
		)
		(property "License" "Apache-2.0"
			(at 144.78 264.16 0)
			(effects
				(font
					(size 1.27 1.27)
					(thickness 0.15)
				)
				(justify left bottom)
				(hide yes)
			)
		)
		(pin "1"
		)
		(instances
			(project "jetson-agx-thor-baseboard"
				(path ""
					(reference "#PWR0305")
					(unit 1)
				)
			)
		)
	)
	(symbol
		(lib_id "antmicroResistors0402:R_200R_0402")
		(at 246.38 161.29 90)
		(unit 1)
		(exclude_from_sim no)
		(in_bom yes)
		(on_board yes)
		(dnp no)
		(fields_autoplaced yes)
		(property "Reference" "R182"
			(at 243.84 157.48 90)
			(effects
				(font
					(size 1.27 1.27)
				)
				(justify left)
			)
		)
		(property "Value" "R_200R_0402"
			(at 259.08 140.97 0)
			(effects
				(font
					(size 1.27 1.27)
					(thickness 0.15)
				)
				(justify left bottom)
				(hide yes)
			)
		)
		(property "Footprint" "antmicro-footprints:R_0402_1005Metric"
			(at 261.62 140.97 0)
			(effects
				(font
					(size 1.27 1.27)
					(thickness 0.15)
				)
				(justify left bottom)
				(hide yes)
			)
		)
		(property "Datasheet" "https://www.bourns.com/docs/product-datasheets/cr.pdf"
			(at 264.16 140.97 0)
			(effects
				(font
					(size 1.27 1.27)
					(thickness 0.15)
				)
				(justify left bottom)
				(hide yes)
			)
		)
		(property "Description" "SMD Chip Resistor, 200 ohm, ± 1%, 62.5 mW, 0402 [1005 Metric], Thick Film, General Purpose"
			(at 246.38 161.29 0)
			(effects
				(font
					(size 1.27 1.27)
				)
				(hide yes)
			)
		)
		(property "Manufacturer" "Bourns"
			(at 269.24 140.97 0)
			(effects
				(font
					(size 1.27 1.27)
					(thickness 0.15)
				)
				(justify left bottom)
				(hide yes)
			)
		)
		(property "MPN" "CR0402-FX-2000GLF"
			(at 266.7 140.97 0)
			(effects
				(font
					(size 1.27 1.27)
					(thickness 0.15)
				)
				(justify left bottom)
				(hide yes)
			)
		)
		(property "Val" "200R"
			(at 243.84 160.02 90)
			(effects
				(font
					(size 1.27 1.27)
					(thickness 0.15)
				)
				(justify left)
			)
		)
		(property "License" "Apache-2.0"
			(at 271.78 140.97 0)
			(effects
				(font
					(size 1.27 1.27)
					(thickness 0.15)
				)
				(justify left bottom)
				(hide yes)
			)
		)
		(property "Author" "Antmicro"
			(at 274.32 140.97 0)
			(effects
				(font
					(size 1.27 1.27)
					(thickness 0.15)
				)
				(justify left bottom)
				(hide yes)
			)
		)
		(property "Tolerance" "1%"
			(at 256.54 140.97 0)
			(effects
				(font
					(size 1.27 1.27)
				)
				(justify left bottom)
				(hide yes)
			)
		)
		(pin "1"
		)
		(pin "2"
		)
		(instances
			(project "jetson-agx-thor-baseboard"
				(path ""
					(reference "R182")
					(unit 1)
				)
			)
		)
	)
	(symbol
		(lib_id "antmicropower:GND")
		(at 212.09 241.3 0)
		(unit 1)
		(exclude_from_sim no)
		(in_bom yes)
		(on_board yes)
		(dnp no)
		(property "Reference" "#PWR0313"
			(at 212.09 247.65 0)
			(effects
				(font
					(size 1.27 1.27)
				)
				(justify left bottom)
				(hide yes)
			)
		)
		(property "Value" "GND"
			(at 212.09 245.11 0)
			(effects
				(font
					(size 1.27 1.27)
					(thickness 0.15)
				)
			)
		)
		(property "Footprint" ""
			(at 220.98 248.92 0)
			(effects
				(font
					(size 1.27 1.27)
					(thickness 0.15)
				)
				(justify left bottom)
				(hide yes)
			)
		)
		(property "Datasheet" ""
			(at 220.98 254 0)
			(effects
				(font
					(size 1.27 1.27)
					(thickness 0.15)
				)
				(justify left bottom)
				(hide yes)
			)
		)
		(property "Description" ""
			(at 212.09 241.3 0)
			(effects
				(font
					(size 1.27 1.27)
				)
				(hide yes)
			)
		)
		(property "Author" "Antmicro"
			(at 220.98 248.92 0)
			(effects
				(font
					(size 1.27 1.27)
					(thickness 0.15)
				)
				(justify left bottom)
				(hide yes)
			)
		)
		(property "License" "Apache-2.0"
			(at 220.98 251.46 0)
			(effects
				(font
					(size 1.27 1.27)
					(thickness 0.15)
				)
				(justify left bottom)
				(hide yes)
			)
		)
		(pin "1"
		)
		(instances
			(project "jetson-agx-thor-baseboard"
				(path ""
					(reference "#PWR0313")
					(unit 1)
				)
			)
		)
	)
	(symbol
		(lib_id "antmicropower:GND")
		(at 99.06 57.15 0)
		(unit 1)
		(exclude_from_sim no)
		(in_bom yes)
		(on_board yes)
		(dnp no)
		(property "Reference" "#PWR0295"
			(at 99.06 63.5 0)
			(effects
				(font
					(size 1.27 1.27)
				)
				(justify left bottom)
				(hide yes)
			)
		)
		(property "Value" "GND"
			(at 99.06 60.96 0)
			(effects
				(font
					(size 1.27 1.27)
					(thickness 0.15)
				)
			)
		)
		(property "Footprint" ""
			(at 107.95 64.77 0)
			(effects
				(font
					(size 1.27 1.27)
					(thickness 0.15)
				)
				(justify left bottom)
				(hide yes)
			)
		)
		(property "Datasheet" ""
			(at 107.95 69.85 0)
			(effects
				(font
					(size 1.27 1.27)
					(thickness 0.15)
				)
				(justify left bottom)
				(hide yes)
			)
		)
		(property "Description" ""
			(at 99.06 57.15 0)
			(effects
				(font
					(size 1.27 1.27)
				)
				(hide yes)
			)
		)
		(property "Author" "Antmicro"
			(at 107.95 64.77 0)
			(effects
				(font
					(size 1.27 1.27)
					(thickness 0.15)
				)
				(justify left bottom)
				(hide yes)
			)
		)
		(property "License" "Apache-2.0"
			(at 107.95 67.31 0)
			(effects
				(font
					(size 1.27 1.27)
					(thickness 0.15)
				)
				(justify left bottom)
				(hide yes)
			)
		)
		(pin "1"
		)
		(instances
			(project "jetson-agx-thor-baseboard"
				(path ""
					(reference "#PWR0295")
					(unit 1)
				)
			)
		)
	)
	(symbol
		(lib_id "antmicroTestPoints:TP_0.75mm_SMD")
		(at 147.32 91.44 0)
		(unit 1)
		(exclude_from_sim no)
		(in_bom no)
		(on_board yes)
		(dnp no)
		(property "Reference" "TP23"
			(at 151.13 91.4399 0)
			(effects
				(font
					(size 1.27 1.27)
				)
				(justify left)
			)
		)
		(property "Value" "TP_0.75mm_SMD"
			(at 157.48 95.25 0)
			(effects
				(font
					(size 1.27 1.27)
					(thickness 0.15)
				)
				(justify left bottom)
				(hide yes)
			)
		)
		(property "Footprint" "antmicro-footprints:TP_SMD_0.75mm"
			(at 157.48 97.79 0)
			(effects
				(font
					(size 1.27 1.27)
					(thickness 0.15)
				)
				(justify left bottom)
				(hide yes)
			)
		)
		(property "Datasheet" ""
			(at 165.1 104.14 0)
			(effects
				(font
					(size 1.27 1.27)
					(thickness 0.15)
				)
				(justify left bottom)
				(hide yes)
			)
		)
		(property "Description" "SMT test point"
			(at 147.32 91.44 0)
			(effects
				(font
					(size 1.27 1.27)
				)
				(hide yes)
			)
		)
		(property "MPN" ""
			(at 158.115 102.87 0)
			(effects
				(font
					(size 1.27 1.27)
					(thickness 0.15)
				)
				(justify left bottom)
				(hide yes)
			)
		)
		(property "Manufacturer" ""
			(at 158.115 97.79 0)
			(effects
				(font
					(size 1.27 1.27)
					(thickness 0.15)
				)
				(justify left bottom)
				(hide yes)
			)
		)
		(property "Author" "Antmicro"
			(at 157.48 100.33 0)
			(effects
				(font
					(size 1.27 1.27)
					(thickness 0.15)
				)
				(justify left bottom)
				(hide yes)
			)
		)
		(property "License" "Apache-2.0"
			(at 157.48 102.87 0)
			(effects
				(font
					(size 1.27 1.27)
					(thickness 0.15)
				)
				(justify left bottom)
				(hide yes)
			)
		)
		(pin "1"
		)
		(instances
			(project "jetson-agx-thor-baseboard"
				(path ""
					(reference "TP23")
					(unit 1)
				)
			)
		)
	)
	(symbol
		(lib_id "antmicroResistors0402:R_0R_0402")
		(at 85.09 104.14 90)
		(unit 1)
		(exclude_from_sim no)
		(in_bom yes)
		(on_board yes)
		(dnp no)
		(property "Reference" "R160"
			(at 86.36 100.33 90)
			(effects
				(font
					(size 1.27 1.27)
				)
				(justify right)
			)
		)
		(property "Value" "R_0R_0402"
			(at 97.79 83.82 0)
			(effects
				(font
					(size 1.27 1.27)
					(thickness 0.15)
				)
				(justify left bottom)
				(hide yes)
			)
		)
		(property "Footprint" "antmicro-footprints:R_0402_1005Metric"
			(at 100.33 83.82 0)
			(effects
				(font
					(size 1.27 1.27)
					(thickness 0.15)
				)
				(justify left bottom)
				(hide yes)
			)
		)
		(property "Datasheet" "https://industrial.panasonic.com/cdbs/www-data/pdf/RDA0000/AOA0000C301.pdf"
			(at 102.87 83.82 0)
			(effects
				(font
					(size 1.27 1.27)
					(thickness 0.15)
				)
				(justify left bottom)
				(hide yes)
			)
		)
		(property "Description" "SMD Chip Resistor, Jumper, 0 ohm, 100 mW, 0402 [1005 Metric], Thick Film, General Purpose"
			(at 85.09 104.14 0)
			(effects
				(font
					(size 1.27 1.27)
				)
				(hide yes)
			)
		)
		(property "Manufacturer" "Panasonic"
			(at 107.95 83.82 0)
			(effects
				(font
					(size 1.27 1.27)
					(thickness 0.15)
				)
				(justify left bottom)
				(hide yes)
			)
		)
		(property "MPN" "ERJ2GE0R00X"
			(at 105.41 83.82 0)
			(effects
				(font
					(size 1.27 1.27)
					(thickness 0.15)
				)
				(justify left bottom)
				(hide yes)
			)
		)
		(property "Val" "0R"
			(at 86.36 102.87 90)
			(effects
				(font
					(size 1.27 1.27)
					(thickness 0.15)
				)
				(justify right)
			)
		)
		(property "License" "Apache-2.0"
			(at 110.49 83.82 0)
			(effects
				(font
					(size 1.27 1.27)
					(thickness 0.15)
				)
				(justify left bottom)
				(hide yes)
			)
		)
		(property "Author" "Antmicro"
			(at 113.03 83.82 0)
			(effects
				(font
					(size 1.27 1.27)
					(thickness 0.15)
				)
				(justify left bottom)
				(hide yes)
			)
		)
		(property "Tolerance" "~"
			(at 95.25 83.82 0)
			(effects
				(font
					(size 1.27 1.27)
				)
				(justify left bottom)
				(hide yes)
			)
		)
		(property "Current" "1A"
			(at 115.57 83.82 0)
			(effects
				(font
					(size 1.27 1.27)
					(thickness 0.15)
				)
				(justify left bottom)
				(hide yes)
			)
		)
		(pin "1"
		)
		(pin "2"
		)
		(instances
			(project "jetson-agx-thor-baseboard"
				(path ""
					(reference "R160")
					(unit 1)
				)
			)
		)
	)
	(symbol
		(lib_id "antmicropower:+3V3")
		(at 212.09 232.41 0)
		(unit 1)
		(exclude_from_sim no)
		(in_bom yes)
		(on_board yes)
		(dnp no)
		(property "Reference" "#PWR0312"
			(at 212.09 236.22 0)
			(effects
				(font
					(size 1.27 1.27)
				)
				(justify left bottom)
				(hide yes)
			)
		)
		(property "Value" "+3V3"
			(at 208.915 228.6 0)
			(effects
				(font
					(size 1.27 1.27)
					(thickness 0.15)
				)
				(justify left)
			)
		)
		(property "Footprint" ""
			(at 227.33 240.03 0)
			(effects
				(font
					(size 1.27 1.27)
					(thickness 0.15)
				)
				(justify left bottom)
				(hide yes)
			)
		)
		(property "Datasheet" ""
			(at 227.33 242.57 0)
			(effects
				(font
					(size 1.27 1.27)
					(thickness 0.15)
				)
				(justify left bottom)
				(hide yes)
			)
		)
		(property "Description" ""
			(at 212.09 232.41 0)
			(effects
				(font
					(size 1.27 1.27)
				)
				(hide yes)
			)
		)
		(property "Author" "Antmicro"
			(at 227.33 234.95 0)
			(effects
				(font
					(size 1.27 1.27)
					(thickness 0.15)
				)
				(justify left bottom)
				(hide yes)
			)
		)
		(property "License" "Apache-2.0"
			(at 227.33 237.49 0)
			(effects
				(font
					(size 1.27 1.27)
					(thickness 0.15)
				)
				(justify left bottom)
				(hide yes)
			)
		)
		(pin "1"
		)
		(instances
			(project "jetson-agx-thor-baseboard"
				(path ""
					(reference "#PWR0312")
					(unit 1)
				)
			)
		)
	)
	(symbol
		(lib_id "antmicroLogicTranslatorsLevelShifters:NTS0102_XSON")
		(at 342.9 238.76 0)
		(unit 1)
		(exclude_from_sim no)
		(in_bom yes)
		(on_board yes)
		(dnp no)
		(fields_autoplaced yes)
		(property "Reference" "U49"
			(at 353.06 231.14 0)
			(effects
				(font
					(size 1.27 1.27)
				)
			)
		)
		(property "Value" "NTS0102_XSON"
			(at 378.46 246.38 0)
			(effects
				(font
					(size 1.27 1.27)
					(thickness 0.15)
				)
				(justify left bottom)
				(hide yes)
			)
		)
		(property "Footprint" "antmicro-footprints:XSON-8_1x1.95mm_P0.5mm"
			(at 378.46 248.92 0)
			(effects
				(font
					(size 1.27 1.27)
					(thickness 0.15)
				)
				(justify left bottom)
				(hide yes)
			)
		)
		(property "Datasheet" "http://www.farnell.com/datasheets/1760723.pdf"
			(at 378.46 251.46 0)
			(effects
				(font
					(size 1.27 1.27)
					(thickness 0.15)
				)
				(justify left bottom)
				(hide yes)
			)
		)
		(property "Description" "Transceiver, 1.65 V to 3.6 V, XSON-8"
			(at 342.9 238.76 0)
			(effects
				(font
					(size 1.27 1.27)
				)
				(hide yes)
			)
		)
		(property "MPN" "NTS0102GT"
			(at 353.06 233.68 0)
			(effects
				(font
					(size 1.27 1.27)
					(thickness 0.15)
				)
			)
		)
		(property "Manufacturer" "NXP"
			(at 378.46 254 0)
			(effects
				(font
					(size 1.27 1.27)
					(thickness 0.15)
				)
				(justify left bottom)
				(hide yes)
			)
		)
		(property "Author" "Antmicro"
			(at 378.46 256.54 0)
			(effects
				(font
					(size 1.27 1.27)
					(thickness 0.15)
				)
				(justify left bottom)
				(hide yes)
			)
		)
		(property "License" "Apache-2.0"
			(at 378.46 259.08 0)
			(effects
				(font
					(size 1.27 1.27)
					(thickness 0.15)
				)
				(justify left bottom)
				(hide yes)
			)
		)
		(pin "1"
		)
		(pin "2"
		)
		(pin "3"
		)
		(pin "4"
		)
		(pin "5"
		)
		(pin "6"
		)
		(pin "7"
		)
		(pin "8"
		)
		(instances
			(project "jetson-agx-thor-baseboard"
				(path ""
					(reference "U49")
					(unit 1)
				)
			)
		)
	)
	(symbol
		(lib_id "antmicropower:GND")
		(at 207.01 256.54 0)
		(unit 1)
		(exclude_from_sim no)
		(in_bom yes)
		(on_board yes)
		(dnp no)
		(property "Reference" "#PWR0309"
			(at 207.01 262.89 0)
			(effects
				(font
					(size 1.27 1.27)
				)
				(justify left bottom)
				(hide yes)
			)
		)
		(property "Value" "GND"
			(at 207.01 260.35 0)
			(effects
				(font
					(size 1.27 1.27)
					(thickness 0.15)
				)
			)
		)
		(property "Footprint" ""
			(at 215.9 264.16 0)
			(effects
				(font
					(size 1.27 1.27)
					(thickness 0.15)
				)
				(justify left bottom)
				(hide yes)
			)
		)
		(property "Datasheet" ""
			(at 215.9 269.24 0)
			(effects
				(font
					(size 1.27 1.27)
					(thickness 0.15)
				)
				(justify left bottom)
				(hide yes)
			)
		)
		(property "Description" ""
			(at 207.01 256.54 0)
			(effects
				(font
					(size 1.27 1.27)
				)
				(hide yes)
			)
		)
		(property "Author" "Antmicro"
			(at 215.9 264.16 0)
			(effects
				(font
					(size 1.27 1.27)
					(thickness 0.15)
				)
				(justify left bottom)
				(hide yes)
			)
		)
		(property "License" "Apache-2.0"
			(at 215.9 266.7 0)
			(effects
				(font
					(size 1.27 1.27)
					(thickness 0.15)
				)
				(justify left bottom)
				(hide yes)
			)
		)
		(pin "1"
		)
		(instances
			(project "jetson-agx-thor-baseboard"
				(path ""
					(reference "#PWR0309")
					(unit 1)
				)
			)
		)
	)
	(symbol
		(lib_id "antmicropower:GND")
		(at 245.11 254 0)
		(unit 1)
		(exclude_from_sim no)
		(in_bom yes)
		(on_board yes)
		(dnp no)
		(property "Reference" "#PWR0316"
			(at 245.11 260.35 0)
			(effects
				(font
					(size 1.27 1.27)
				)
				(justify left bottom)
				(hide yes)
			)
		)
		(property "Value" "GND"
			(at 245.11 257.81 0)
			(effects
				(font
					(size 1.27 1.27)
					(thickness 0.15)
				)
			)
		)
		(property "Footprint" ""
			(at 254 261.62 0)
			(effects
				(font
					(size 1.27 1.27)
					(thickness 0.15)
				)
				(justify left bottom)
				(hide yes)
			)
		)
		(property "Datasheet" ""
			(at 254 266.7 0)
			(effects
				(font
					(size 1.27 1.27)
					(thickness 0.15)
				)
				(justify left bottom)
				(hide yes)
			)
		)
		(property "Description" ""
			(at 245.11 254 0)
			(effects
				(font
					(size 1.27 1.27)
				)
				(hide yes)
			)
		)
		(property "Author" "Antmicro"
			(at 254 261.62 0)
			(effects
				(font
					(size 1.27 1.27)
					(thickness 0.15)
				)
				(justify left bottom)
				(hide yes)
			)
		)
		(property "License" "Apache-2.0"
			(at 254 264.16 0)
			(effects
				(font
					(size 1.27 1.27)
					(thickness 0.15)
				)
				(justify left bottom)
				(hide yes)
			)
		)
		(pin "1"
		)
		(instances
			(project "jetson-agx-thor-baseboard"
				(path ""
					(reference "#PWR0316")
					(unit 1)
				)
			)
		)
	)
	(symbol
		(lib_id "antmicropower:GND")
		(at 110.49 110.49 0)
		(unit 1)
		(exclude_from_sim no)
		(in_bom yes)
		(on_board yes)
		(dnp no)
		(property "Reference" "#PWR0300"
			(at 110.49 116.84 0)
			(effects
				(font
					(size 1.27 1.27)
				)
				(justify left bottom)
				(hide yes)
			)
		)
		(property "Value" "GND"
			(at 110.49 114.3 0)
			(effects
				(font
					(size 1.27 1.27)
					(thickness 0.15)
				)
			)
		)
		(property "Footprint" ""
			(at 119.38 118.11 0)
			(effects
				(font
					(size 1.27 1.27)
					(thickness 0.15)
				)
				(justify left bottom)
				(hide yes)
			)
		)
		(property "Datasheet" ""
			(at 119.38 123.19 0)
			(effects
				(font
					(size 1.27 1.27)
					(thickness 0.15)
				)
				(justify left bottom)
				(hide yes)
			)
		)
		(property "Description" ""
			(at 110.49 110.49 0)
			(effects
				(font
					(size 1.27 1.27)
				)
				(hide yes)
			)
		)
		(property "Author" "Antmicro"
			(at 119.38 118.11 0)
			(effects
				(font
					(size 1.27 1.27)
					(thickness 0.15)
				)
				(justify left bottom)
				(hide yes)
			)
		)
		(property "License" "Apache-2.0"
			(at 119.38 120.65 0)
			(effects
				(font
					(size 1.27 1.27)
					(thickness 0.15)
				)
				(justify left bottom)
				(hide yes)
			)
		)
		(pin "1"
		)
		(instances
			(project "jetson-agx-thor-baseboard"
				(path ""
					(reference "#PWR0300")
					(unit 1)
				)
			)
		)
	)
	(symbol
		(lib_id "antmicropower:+3V3")
		(at 114.3 134.62 0)
		(unit 1)
		(exclude_from_sim no)
		(in_bom yes)
		(on_board yes)
		(dnp no)
		(property "Reference" "#PWR0302"
			(at 114.3 138.43 0)
			(effects
				(font
					(size 1.27 1.27)
				)
				(justify left bottom)
				(hide yes)
			)
		)
		(property "Value" "+3V3"
			(at 113.665 130.81 0)
			(effects
				(font
					(size 1.27 1.27)
					(thickness 0.15)
				)
			)
		)
		(property "Footprint" ""
			(at 129.54 142.24 0)
			(effects
				(font
					(size 1.27 1.27)
					(thickness 0.15)
				)
				(justify left bottom)
				(hide yes)
			)
		)
		(property "Datasheet" ""
			(at 129.54 144.78 0)
			(effects
				(font
					(size 1.27 1.27)
					(thickness 0.15)
				)
				(justify left bottom)
				(hide yes)
			)
		)
		(property "Description" ""
			(at 114.3 134.62 0)
			(effects
				(font
					(size 1.27 1.27)
				)
				(hide yes)
			)
		)
		(property "Author" "Antmicro"
			(at 129.54 137.16 0)
			(effects
				(font
					(size 1.27 1.27)
					(thickness 0.15)
				)
				(justify left bottom)
				(hide yes)
			)
		)
		(property "License" "Apache-2.0"
			(at 129.54 139.7 0)
			(effects
				(font
					(size 1.27 1.27)
					(thickness 0.15)
				)
				(justify left bottom)
				(hide yes)
			)
		)
		(pin "1"
		)
		(instances
			(project "jetson-agx-thor-baseboard"
				(path ""
					(reference "#PWR0302")
					(unit 1)
				)
			)
		)
	)
	(symbol
		(lib_id "antmicroResistors0402:R_4k7_0402")
		(at 259.08 252.73 90)
		(unit 1)
		(exclude_from_sim no)
		(in_bom yes)
		(on_board yes)
		(dnp no)
		(property "Reference" "R180"
			(at 260.35 248.92 90)
			(effects
				(font
					(size 1.27 1.27)
				)
				(justify right)
			)
		)
		(property "Value" "R_4k7_0402"
			(at 271.78 232.41 0)
			(effects
				(font
					(size 1.27 1.27)
					(thickness 0.15)
				)
				(justify left bottom)
				(hide yes)
			)
		)
		(property "Footprint" "antmicro-footprints:R_0402_1005Metric"
			(at 274.32 232.41 0)
			(effects
				(font
					(size 1.27 1.27)
					(thickness 0.15)
				)
				(justify left bottom)
				(hide yes)
			)
		)
		(property "Datasheet" "https://www.bourns.com/docs/product-datasheets/cr.pdf"
			(at 276.86 232.41 0)
			(effects
				(font
					(size 1.27 1.27)
					(thickness 0.15)
				)
				(justify left bottom)
				(hide yes)
			)
		)
		(property "Description" "SMD Chip Resistor, 4.7 kohm, ± 1%, 62.5 mW, 0402 [1005 Metric], Thick Film, General Purpose"
			(at 259.08 252.73 0)
			(effects
				(font
					(size 1.27 1.27)
				)
				(hide yes)
			)
		)
		(property "Manufacturer" "Bourns"
			(at 281.94 232.41 0)
			(effects
				(font
					(size 1.27 1.27)
					(thickness 0.15)
				)
				(justify left bottom)
				(hide yes)
			)
		)
		(property "MPN" "CR0402-FX-4701GLF"
			(at 279.4 232.41 0)
			(effects
				(font
					(size 1.27 1.27)
					(thickness 0.15)
				)
				(justify left bottom)
				(hide yes)
			)
		)
		(property "Val" "4k7"
			(at 260.35 251.46 90)
			(effects
				(font
					(size 1.27 1.27)
					(thickness 0.15)
				)
				(justify right)
			)
		)
		(property "License" "Apache-2.0"
			(at 284.48 232.41 0)
			(effects
				(font
					(size 1.27 1.27)
					(thickness 0.15)
				)
				(justify left bottom)
				(hide yes)
			)
		)
		(property "Author" "Antmicro"
			(at 287.02 232.41 0)
			(effects
				(font
					(size 1.27 1.27)
					(thickness 0.15)
				)
				(justify left bottom)
				(hide yes)
			)
		)
		(property "Tolerance" "1%"
			(at 269.24 232.41 0)
			(effects
				(font
					(size 1.27 1.27)
				)
				(justify left bottom)
				(hide yes)
			)
		)
		(pin "1"
		)
		(pin "2"
		)
		(instances
			(project "jetson-agx-thor-baseboard"
				(path ""
					(reference "R180")
					(unit 1)
				)
			)
		)
	)
	(symbol
		(lib_id "antmicropower:+3V3")
		(at 372.11 195.58 0)
		(unit 1)
		(exclude_from_sim no)
		(in_bom yes)
		(on_board yes)
		(dnp no)
		(property "Reference" "#PWR0335"
			(at 372.11 199.39 0)
			(effects
				(font
					(size 1.27 1.27)
				)
				(justify left bottom)
				(hide yes)
			)
		)
		(property "Value" "+3V3"
			(at 368.935 191.77 0)
			(effects
				(font
					(size 1.27 1.27)
					(thickness 0.15)
				)
				(justify left)
			)
		)
		(property "Footprint" ""
			(at 387.35 203.2 0)
			(effects
				(font
					(size 1.27 1.27)
					(thickness 0.15)
				)
				(justify left bottom)
				(hide yes)
			)
		)
		(property "Datasheet" ""
			(at 387.35 205.74 0)
			(effects
				(font
					(size 1.27 1.27)
					(thickness 0.15)
				)
				(justify left bottom)
				(hide yes)
			)
		)
		(property "Description" ""
			(at 372.11 195.58 0)
			(effects
				(font
					(size 1.27 1.27)
				)
				(hide yes)
			)
		)
		(property "Author" "Antmicro"
			(at 387.35 198.12 0)
			(effects
				(font
					(size 1.27 1.27)
					(thickness 0.15)
				)
				(justify left bottom)
				(hide yes)
			)
		)
		(property "License" "Apache-2.0"
			(at 387.35 200.66 0)
			(effects
				(font
					(size 1.27 1.27)
					(thickness 0.15)
				)
				(justify left bottom)
				(hide yes)
			)
		)
		(pin "1"
		)
		(instances
			(project "jetson-agx-thor-baseboard"
				(path ""
					(reference "#PWR0335")
					(unit 1)
				)
			)
		)
	)
)
